G04 ================== begin FILE IDENTIFICATION RECORD ==================*
G04 Layout Name:  D:/<user>/Wistron_project/16316-1/gbr-0621/16316-1.brd*
G04 Film Name:    SE_REF_L8*
G04 File Format:  Gerber RS274X*
G04 File Origin:  Cadence Allegro 16.5-S056*
G04 Origin Date:  Wed Jun 21 09:32:41 2017*
G04 *
G04 Layer:  BOARD GEOMETRY/SE_REF_L8_TBL*
G04 Layer:  BOARD GEOMETRY/SE_REF_L8_BOTTOM*
G04 Layer:  BOARD GEOMETRY/PANEL_OUTLINE*
G04 *
G04 Offset:    (0.00 0.00)*
G04 Mirror:    No*
G04 Mode:      Positive*
G04 Rotation:  0*
G04 FullContactRelief:  No*
G04 UndefLineWidth:     6.00*
G04 ================== end FILE IDENTIFICATION RECORD ====================*
%FSLAX35Y35*MOIN*%
%IR0*IPPOS*OFA0.00000B0.00000*MIA0B0*SFA1.00000B1.00000*%
%ADD10C,.02*%
%ADD11C,.005*%
%ADD12C,.006*%
G75*
%LPD*%
G75*
G54D10*
G01X877071Y467216D02*
X1594571D01*
G01X877071Y536516D02*
Y467216D01*
G01Y536516D02*
X1594571D01*
G01X877071Y501866D02*
X1594571D01*
G01X1052071Y536516D02*
Y467216D01*
G01X1279571Y536516D02*
Y467216D01*
G01X1384571Y536516D02*
Y467216D01*
G01X1594571Y536516D02*
Y467216D01*
G54D11*
G01X35440Y239843D02*
X35405Y239808D01*
G01X35440Y264340D02*
Y239843D01*
G01X56700Y285600D02*
X35440Y264340D01*
G01X56700Y364100D02*
Y285600D01*
G01X32469Y264198D02*
Y250280D01*
G01X54700Y286429D02*
X32469Y264198D01*
G01X54700Y364929D02*
Y286429D01*
G01X62600Y370000D02*
X56700Y364100D01*
G01X110508Y370000D02*
X62600D01*
G01X61771Y372000D02*
X54700Y364929D01*
G01X90757Y372000D02*
X61771D01*
G01X136800Y348000D02*
X114159Y370641D01*
G01X230400Y348000D02*
X136800D01*
G01X133694Y343985D02*
X109679Y368000D01*
G01X237682Y343985D02*
X133694D01*
G01X134523Y345985D02*
X110508Y370000D01*
G01X233527Y345985D02*
X134523D01*
G01X105697Y365104D02*
X121506Y349295D01*
G01X126048Y344753D02*
X121506Y349295D01*
G01X130097Y344753D02*
X126048D01*
G01X132865Y341985D02*
X130097Y344753D01*
G01X235486Y341985D02*
X132865D01*
G01X103266Y362988D02*
X114258Y351996D01*
G01X124216Y342038D02*
X114258Y351996D01*
G01X129983Y342038D02*
X124216D01*
G01X133521Y338500D02*
X129983Y342038D01*
G01X231500Y338500D02*
X133521D01*
G01X100471Y361783D02*
X99266Y362988D01*
G01X122265Y339988D02*
X100471Y361782D01*
G01X129133Y339988D02*
X122265D01*
G01X132621Y336500D02*
X230000D01*
G01X129133Y339988D02*
X132621Y336500D01*
G01X114159Y389676D02*
X112638Y391197D01*
G01X114159Y370641D02*
Y389676D01*
G01X82976Y368000D02*
X78171Y363195D01*
G01X109679Y368000D02*
X82976D01*
G01X98604Y379847D02*
X90757Y372000D01*
G01X98604Y387075D02*
Y379847D01*
G01X102679Y391150D02*
X98604Y387075D01*
G01X84080Y365104D02*
X105697D01*
G01X82171Y363195D02*
X84080Y365104D01*
G01X100471Y361782D02*
Y361783D01*
G01X241556Y340111D02*
X237682Y343985D01*
G01X240300Y352758D02*
X233527Y345985D01*
G01X261358Y352758D02*
X240300D01*
G01X272900Y364300D02*
X261358Y352758D01*
G01X237483Y339988D02*
X235486Y341985D01*
G01X233400Y336600D02*
X231500Y338500D01*
G01X306175Y297650D02*
Y301161D01*
G01X283000Y286250D02*
X287500D01*
G01X295250D02*
X296000Y287000D01*
G01X287500Y286250D02*
X295250D01*
G01X296330Y294500D02*
Y297650D01*
G01X296000Y294170D02*
X296330Y294500D01*
G01X296000Y287000D02*
Y294170D01*
G01X300270Y300830D02*
Y297650D01*
G01X312080Y303280D02*
Y297650D01*
G01X321920D02*
Y301908D01*
G01X310200Y297740D02*
X310110Y297650D01*
G01X310200Y310629D02*
Y297740D01*
G01X314045Y297650D02*
Y302900D01*
G01X304205Y301566D02*
Y297650D01*
G01X323890D02*
Y302675D01*
G01X319955Y297650D02*
Y301594D01*
G01X294360Y307227D02*
Y297650D01*
G01X317985Y301487D02*
Y297650D01*
G01X308140Y305160D02*
Y297650D01*
G01X302235Y300071D02*
Y297650D01*
G01X313853Y330600D02*
X319100D01*
G01X312400Y329147D02*
X313853Y330600D01*
G01X312400Y315658D02*
Y329147D01*
G01X308110Y311368D02*
X312400Y315658D01*
G01X308110Y308723D02*
Y311368D01*
G01X305600Y306213D02*
X308110Y308723D01*
G01X305600Y303500D02*
Y306213D01*
G01X306195Y302905D02*
X305600Y303500D01*
G01X306195Y301181D02*
Y302905D01*
G01X306175Y301161D02*
X306195Y301181D01*
G01X299200Y301900D02*
X300270Y300830D01*
G01X299200Y309238D02*
Y301900D01*
G01X301628Y311666D02*
X299200Y309238D01*
G01X301628Y320511D02*
Y311666D01*
G01X315800Y341950D02*
X316050Y342200D01*
G01X315800Y336035D02*
Y341950D01*
G01X314700Y334935D02*
X315800Y336035D01*
G01X314700Y333400D02*
Y334935D01*
G01X314200Y332900D02*
X314700Y333400D01*
G01X310600Y332900D02*
X314200D01*
G01X310300Y332600D02*
X310600Y332900D01*
G01X310300Y316600D02*
Y332600D01*
G01X309800Y316100D02*
X310300Y316600D01*
G01X308800Y316100D02*
X309800D01*
G01X308300Y316600D02*
X308800Y316100D01*
G01X308300Y332600D02*
Y316600D01*
G01X307800Y333100D02*
X308300Y332600D01*
G01X306800Y333100D02*
X307800D01*
G01X306300Y332600D02*
X306800Y333100D01*
G01X306300Y327000D02*
Y332600D01*
G01X305800Y326500D02*
X306300Y327000D01*
G01X304800Y326500D02*
X305800D01*
G01X304300Y327000D02*
X304800Y326500D01*
G01X304300Y328379D02*
Y327000D01*
G01X303700Y328979D02*
X304300Y328379D01*
G01X301300Y328979D02*
X303700D01*
G01X300800Y329479D02*
X301300Y328979D01*
G01X300800Y330479D02*
Y329479D01*
G01X301300Y330979D02*
X300800Y330479D01*
G01X303700Y330979D02*
X301300D01*
G01X304200Y331479D02*
X303700Y330979D01*
G01X304200Y332500D02*
Y331479D01*
G01X303700Y333000D02*
X304200Y332500D01*
G01X301300Y333000D02*
X303700D01*
G01X300800Y333500D02*
X301300Y333000D01*
G01X300800Y334800D02*
Y333500D01*
G01X301300Y335300D02*
X300800Y334800D01*
G01X310900Y335300D02*
X301300D01*
G01X313300Y337700D02*
X310900Y335300D01*
G01X313300Y361100D02*
Y337700D01*
G01X318538Y366338D02*
X313300Y361100D01*
G01X312200Y303400D02*
X312080Y303280D01*
G01X312200Y309800D02*
Y303400D01*
G01X314300Y311900D02*
X312200Y309800D01*
G01X322956Y322856D02*
X325500Y325400D01*
G01X322248Y322856D02*
X322956D01*
G01X321456Y323648D02*
X322248Y322856D01*
G01X320748Y323648D02*
X321456D01*
G01X320041Y322941D02*
X320748Y323648D01*
G01X320041Y322233D02*
Y322941D01*
G01X320833Y321441D02*
X320041Y322233D01*
G01X320833Y320733D02*
Y321441D01*
G01X320000Y319900D02*
X320833Y320733D01*
G01X320000Y303828D02*
Y319900D01*
G01X321920Y301908D02*
X320000Y303828D01*
G01X305147Y354706D02*
Y362647D01*
G01X290800Y352800D02*
X297021Y346579D01*
G01X290800Y365100D02*
Y352800D01*
G01X325100Y306814D02*
X324100Y307814D01*
G01X314500Y314929D02*
X310200Y310629D01*
G01X314500Y324251D02*
Y314929D01*
G01X315300Y360271D02*
X320538Y365509D01*
G01X315300Y346000D02*
Y360271D01*
G01X317900Y343400D02*
X315300Y346000D01*
G01X317900Y338256D02*
Y343400D01*
G01X319128Y337028D02*
X317900Y338256D01*
G01X320078Y337028D02*
X319128D01*
G01X320650Y336456D02*
X320078Y337028D01*
G01X304220Y301581D02*
X304205Y301566D01*
G01X303600Y302201D02*
X304220Y301581D01*
G01X303600Y307552D02*
Y302201D01*
G01X305628Y309580D02*
X303600Y307552D01*
G01X305628Y320511D02*
Y309580D01*
G01X322000Y317900D02*
X325500Y321400D01*
G01X322000Y304565D02*
Y317900D01*
G01X323890Y302675D02*
X322000Y304565D01*
G01X319800Y360908D02*
Y361908D01*
G01X320300Y360408D02*
X319800Y360908D01*
G01X322400Y360408D02*
X320300D01*
G01X322900Y359908D02*
X322400Y360408D01*
G01X322900Y358908D02*
Y359908D01*
G01X322400Y358408D02*
X322900Y358908D01*
G01X317800Y358408D02*
X322400D01*
G01X317300Y357908D02*
X317800Y358408D01*
G01X317300Y356908D02*
Y357908D01*
G01X317800Y356408D02*
X317300Y356908D01*
G01X320200Y356408D02*
X317800D01*
G01X320700Y355908D02*
X320200Y356408D01*
G01X320700Y354908D02*
Y355908D01*
G01X320200Y354408D02*
X320700Y354908D01*
G01X317800Y354408D02*
X320200D01*
G01X317300Y353908D02*
X317800Y354408D01*
G01X317300Y352908D02*
Y353908D01*
G01X317800Y352408D02*
X317300Y352908D01*
G01X319900Y352408D02*
X317800D01*
G01X320400Y351908D02*
X319900Y352408D01*
G01X320400Y350908D02*
Y351908D01*
G01X319900Y350408D02*
X320400Y350908D01*
G01X317800Y350408D02*
X319900D01*
G01X317300Y349908D02*
X317800Y350408D01*
G01X317300Y347669D02*
Y349908D01*
G01X317800Y347169D02*
X317300Y347669D01*
G01X319550Y347169D02*
X317800D01*
G01X311300Y340051D02*
Y362671D01*
G01X310200Y338951D02*
X311300Y340051D01*
G01X310200Y337600D02*
Y338951D01*
G01X317900Y324351D02*
X314400Y327851D01*
G01X317900Y303649D02*
Y324351D01*
G01X319955Y301594D02*
X317900Y303649D01*
G01X309300Y340880D02*
Y363500D01*
G01X306060Y337640D02*
X309300Y340880D01*
G01X301500Y339441D02*
Y337500D01*
G01X305500Y343441D02*
X301500Y339441D01*
G01X305500Y351300D02*
Y343441D01*
G01X305000Y351800D02*
X305500Y351300D01*
G01X304000Y351800D02*
X305000D01*
G01X303500Y351300D02*
X304000Y351800D01*
G01X303500Y345441D02*
Y351300D01*
G01X303000Y344941D02*
X303500Y345441D01*
G01X302000Y344941D02*
X303000D01*
G01X301500Y345441D02*
X302000Y344941D01*
G01X301500Y350800D02*
Y345441D01*
G01X298662Y353638D02*
X301500Y350800D01*
G01X298662Y364700D02*
Y353638D01*
G01X300662Y354700D02*
Y364700D01*
G01X301162Y354200D02*
X300662Y354700D01*
G01X302162Y354200D02*
X301162D01*
G01X302662Y354700D02*
X302162Y354200D01*
G01X302662Y363718D02*
Y354700D01*
G01X298800Y311667D02*
X294360Y307227D01*
G01X298800Y336650D02*
Y311667D01*
G01X287350Y348100D02*
X298800Y336650D01*
G01X287350Y351200D02*
Y348100D01*
G01X314241Y305231D02*
X317985Y301487D01*
G01X314241Y308459D02*
Y305231D01*
G01X308180Y305200D02*
X308140Y305160D01*
G01X324500Y316544D02*
X326600D01*
G01X324000Y316044D02*
X324500Y316544D01*
G01X324000Y315044D02*
Y316044D01*
G01X324500Y314544D02*
X324000Y315044D01*
G01X326600Y314544D02*
X324500D01*
G01Y312544D02*
X326600D01*
G01X324000Y312044D02*
X324500Y312544D01*
G01X324000Y311044D02*
Y312044D01*
G01X324500Y310544D02*
X324000Y311044D01*
G01X326600Y310544D02*
X324500D01*
G01X287350Y357700D02*
Y364479D01*
G01X302245Y300081D02*
X302235Y300071D01*
G01X302245Y301355D02*
Y300081D01*
G01X301600Y302000D02*
X302245Y301355D01*
G01X301600Y308758D02*
Y302000D01*
G01X303628Y310786D02*
X301600Y308758D01*
G01X303628Y322511D02*
Y310786D01*
G01X305628Y324511D02*
X303628Y322511D01*
G01X323000Y326200D02*
X325400Y328600D01*
G01X319200Y326200D02*
X323000D01*
G01X318700Y326700D02*
X319200Y326200D01*
G01X318700Y328100D02*
Y326700D01*
G01X319200Y328600D02*
X318700Y328100D01*
G01X321500Y328600D02*
X319200D01*
G01X322500Y329600D02*
X321500Y328600D01*
G01X322500Y332306D02*
Y329600D01*
G01X322200Y332606D02*
X322500Y332306D01*
G01X317200Y332606D02*
X322200D01*
G01X316700Y333106D02*
X317200Y332606D01*
G01X316700Y334106D02*
Y333106D01*
G01X317200Y334606D02*
X316700Y334106D01*
G01X321706Y334606D02*
X317200D01*
G01X322500Y335400D02*
X321706Y334606D01*
G01X322500Y338691D02*
Y335400D01*
G01X322000Y339191D02*
X322500Y338691D01*
G01X320400Y339191D02*
X322000D01*
G01X319900Y339691D02*
X320400Y339191D01*
G01X319900Y340691D02*
Y339691D01*
G01X320400Y341191D02*
X319900Y340691D01*
G01X322000Y341191D02*
X320400D01*
G01X322500Y341691D02*
X322000Y341191D01*
G01X322500Y342691D02*
Y341691D01*
G01X322000Y343191D02*
X322500Y342691D01*
G01X320400Y343191D02*
X322000D01*
G01X319900Y343691D02*
X320400Y343191D01*
G01X319900Y344691D02*
Y343691D01*
G01X320400Y345191D02*
X319900Y344691D01*
G01X322000Y345191D02*
X320400D01*
G01X322500Y345691D02*
X322000Y345191D01*
G01X322500Y353700D02*
Y345691D01*
G01X318538Y369262D02*
Y366338D01*
G01X318015Y369785D02*
X318538Y369262D01*
G01X318015Y370329D02*
Y369785D01*
G01X317985Y370359D02*
X318015Y370329D01*
G01X317985Y373350D02*
Y370359D01*
G01X304205Y373350D02*
Y382450D01*
G01X321467Y385281D02*
Y383273D01*
G01X320256Y386492D02*
X321467Y385281D01*
G01X316786Y386492D02*
X320256D01*
G01X321467Y380438D02*
Y383273D01*
G01X319955Y378926D02*
X321467Y380438D01*
G01X319955Y373350D02*
Y378926D01*
G01X312080Y380642D02*
Y373350D01*
G01X312580Y381142D02*
X312080Y380642D01*
G01X314700Y381142D02*
X312580D01*
G01X315200Y381642D02*
X314700Y381142D01*
G01X315200Y382642D02*
Y381642D01*
G01X314700Y383142D02*
X315200Y382642D01*
G01X313000Y383142D02*
X314700D01*
G01X312398Y383744D02*
X313000Y383142D01*
G01X312398Y386479D02*
Y383744D01*
G01X310110Y370359D02*
Y373350D01*
G01X310140Y370329D02*
X310110Y370359D01*
G01X310140Y368367D02*
Y370329D01*
G01X310110Y368337D02*
X310140Y368367D01*
G01X310110Y367610D02*
Y368337D01*
G01X305147Y362647D02*
X310110Y367610D01*
G01X324764Y405064D02*
X332040Y412340D01*
G01X323448Y405064D02*
X324764D01*
G01X296330Y370630D02*
X290800Y365100D01*
G01X296330Y373350D02*
Y370630D01*
G01X302235Y377065D02*
Y373350D01*
G01X302205Y377095D02*
X302235Y377065D01*
G01X302205Y383979D02*
Y377095D01*
G01X301705Y384479D02*
X302205Y383979D01*
G01X294442Y384479D02*
X301705D01*
G01X293942Y384979D02*
X294442Y384479D01*
G01X293942Y385979D02*
Y384979D01*
G01X294442Y386479D02*
X293942Y385979D01*
G01X304398Y386479D02*
X294442D01*
G01X272900Y421400D02*
Y364300D01*
G01X269939Y424361D02*
X272900Y421400D01*
G01X321920Y370220D02*
Y373350D01*
G01X320567Y368867D02*
X321920Y370220D01*
G01X320567Y366067D02*
Y368867D01*
G01X320538Y366038D02*
X320567Y366067D01*
G01X320538Y365509D02*
Y366038D01*
G01X298300Y377805D02*
X300019Y379524D01*
G01X298300Y373350D02*
Y377805D01*
G01X294360D02*
X296079Y379524D01*
G01X294360Y373350D02*
Y377805D01*
G01X323890Y370359D02*
Y373350D01*
G01X323860Y370329D02*
X323890Y370359D01*
G01X323860Y369260D02*
Y370329D01*
G01X322567Y367967D02*
X323860Y369260D01*
G01X322567Y363175D02*
Y367967D01*
G01X321800Y362408D02*
X322567Y363175D01*
G01X320300Y362408D02*
X321800D01*
G01X319800Y361908D02*
X320300Y362408D01*
G01X316015Y367515D02*
Y373350D01*
G01X315400Y366900D02*
X316015Y367515D01*
G01X315400Y366771D02*
Y366900D01*
G01X311300Y362671D02*
X315400Y366771D01*
G01X306175Y376834D02*
Y373350D01*
G01X308398Y379057D02*
X306175Y376834D01*
G01X308398Y386479D02*
Y379057D01*
G01X314045Y369745D02*
Y373350D01*
G01X313400Y369100D02*
X314045Y369745D01*
G01X313400Y367600D02*
Y369100D01*
G01X309300Y363500D02*
X313400Y367600D01*
G01X300270Y370001D02*
Y373350D01*
G01X294069Y363800D02*
X300270Y370001D01*
G01X292800Y363800D02*
X294069D01*
G01X299162Y365200D02*
X298662Y364700D01*
G01X300162Y365200D02*
X299162D01*
G01X300662Y364700D02*
X300162Y365200D01*
G01X308140Y369196D02*
X302662Y363718D01*
G01X308140Y373350D02*
Y369196D01*
G01X292395Y369524D02*
Y373350D01*
G01X287350Y364479D02*
X292395Y369524D01*
G01X268004Y424361D02*
X269939D01*
G01X337670Y297650D02*
Y303354D01*
G01X333730Y308307D02*
Y297650D01*
G01X325860D02*
Y302756D01*
G01X339640Y305240D02*
Y297650D01*
G01X331765Y301702D02*
Y297650D01*
G01X329795Y300826D02*
Y297650D01*
G01X327825D02*
Y302970D01*
G01X371648Y341070D02*
Y335023D01*
G01X371160Y331500D02*
Y329035D01*
G01X371648Y331988D02*
X371160Y331500D01*
G01X371648Y335023D02*
Y331988D01*
G01X333800Y311905D02*
X335882Y309823D01*
G01X333800Y331370D02*
Y311905D01*
G01X332300Y332870D02*
X333800Y331370D01*
G01X332300Y341800D02*
Y332870D01*
G01X330000Y344100D02*
X332300Y341800D01*
G01X330000Y345800D02*
Y344100D01*
G01X335882Y305142D02*
Y309823D01*
G01X337670Y303354D02*
X335882Y305142D01*
G01X371160Y320965D02*
Y314500D01*
G01Y312754D02*
Y314500D01*
G01X373067Y310847D02*
X371160Y312754D01*
G01X376734Y310847D02*
X373067D01*
G01X358550Y318035D02*
Y319900D01*
G01X356315Y315800D02*
X358550Y318035D01*
G01X355200Y315800D02*
X356315D01*
G01X351050Y317136D02*
Y319900D01*
G01X349764Y315850D02*
X351050Y317136D01*
G01X347750Y315850D02*
X349764D01*
G01X340000Y343700D02*
X339000Y344700D01*
G01X352900Y343700D02*
X340000D01*
G01X365700Y356500D02*
X352900Y343700D01*
G01X365700Y377900D02*
Y356500D01*
G01X368800Y353900D02*
Y377900D01*
G01X356500Y341600D02*
X368800Y353900D01*
G01X337124Y341600D02*
X356500D01*
G01X332512Y346212D02*
X337124Y341600D01*
G01X331670Y347053D02*
X332512Y346212D01*
G01X331670Y368831D02*
Y347053D01*
G01X351050Y333256D02*
Y330500D01*
G01X348596Y335710D02*
X351050Y333256D01*
G01X348596Y337250D02*
Y335710D01*
G01X366040Y318440D02*
Y320965D01*
G01X363400Y315800D02*
X366040Y318440D01*
G01X331364Y310673D02*
X333730Y308307D01*
G01X331364Y328747D02*
Y310673D01*
G01X330200Y329911D02*
X331364Y328747D01*
G01X330200Y340808D02*
Y329911D01*
G01X328408Y342600D02*
X330200Y340808D01*
G01X327400Y342600D02*
X328408D01*
G01X325100Y303516D02*
Y306814D01*
G01X325860Y302756D02*
X325100Y303516D01*
G01X354800Y332865D02*
Y330500D01*
G01X352396Y335269D02*
X354800Y332865D01*
G01X352396Y337200D02*
Y335269D01*
G01X338300Y361378D02*
Y362378D01*
G01X337800Y360878D02*
X338300Y361378D01*
G01X336170Y360878D02*
X337800D01*
G01X335670Y360378D02*
X336170Y360878D01*
G01X335670Y359378D02*
Y360378D01*
G01X336170Y358878D02*
X335670Y359378D01*
G01X337800Y358878D02*
X336170D01*
G01X338300Y358378D02*
X337800Y358878D01*
G01X338300Y357378D02*
Y358378D01*
G01X337800Y356878D02*
X338300Y357378D01*
G01X336170Y356878D02*
X337800D01*
G01X335670Y356378D02*
X336170Y356878D01*
G01X335670Y354130D02*
Y356378D01*
G01X336500Y353300D02*
X335670Y354130D01*
G01X340906Y353300D02*
X336500D01*
G01X341506Y352700D02*
X340906Y353300D01*
G01X341506Y351500D02*
Y352700D01*
G01X341906Y351100D02*
X341506Y351500D01*
G01X343106Y351100D02*
X341906D01*
G01X343506Y351500D02*
X343106Y351100D01*
G01X343506Y352700D02*
Y351500D01*
G01X344106Y353300D02*
X343506Y352700D01*
G01X348800Y353300D02*
X344106D01*
G01X350893Y355393D02*
X348800Y353300D01*
G01X350893Y356101D02*
Y355393D01*
G01X350401Y356593D02*
X350893Y356101D01*
G01X350401Y357301D02*
Y356593D01*
G01X351108Y358008D02*
X350401Y357301D01*
G01X351816Y358008D02*
X351108D01*
G01X352308Y357516D02*
X351816Y358008D01*
G01X353016Y357516D02*
X352308D01*
G01X354500Y359000D02*
X353016Y357516D01*
G01X354500Y381100D02*
Y359000D01*
G01X358400Y358300D02*
Y381100D01*
G01X349873Y349773D02*
X358400Y358300D01*
G01X345700Y349773D02*
X349873D01*
G01X362862Y319462D02*
X359200Y315800D01*
G01X362862Y323841D02*
Y319462D01*
G01X366040Y327019D02*
X362862Y323841D01*
G01X366040Y329035D02*
Y327019D01*
G01X327670Y356400D02*
Y367173D01*
G01X327170Y355900D02*
X327670Y356400D01*
G01X325700Y355900D02*
X327170D01*
G01X325200Y356400D02*
X325700Y355900D01*
G01X325200Y365100D02*
Y356400D01*
G01X333670Y348630D02*
Y370329D01*
G01X335400Y346900D02*
X333670Y348630D01*
G01X341800Y346900D02*
X335400D01*
G01X343000Y345700D02*
X341800Y346900D01*
G01X351900Y345700D02*
X343000D01*
G01X363700Y357500D02*
X351900Y345700D01*
G01X363700Y389224D02*
Y357500D01*
G01X360400Y357471D02*
Y383224D01*
G01X350629Y347700D02*
X360400Y357471D01*
G01X344600Y347700D02*
X350629D01*
G01X343200Y349100D02*
X344600Y347700D01*
G01X340000Y349100D02*
X343200D01*
G01X339500Y349600D02*
X340000Y349100D01*
G01X337600Y349600D02*
X339500D01*
G01X340573Y306173D02*
X339640Y305240D01*
G01X345700Y306173D02*
X340573D01*
G01X346200Y306673D02*
X345700Y306173D01*
G01X346200Y307673D02*
Y306673D01*
G01X345700Y308173D02*
X346200Y307673D01*
G01X338700Y308173D02*
X345700D01*
G01X338200Y308673D02*
X338700Y308173D01*
G01X338200Y309673D02*
Y308673D01*
G01X338700Y310173D02*
X338200Y309673D01*
G01X346000Y310173D02*
X338700D01*
G01X346500Y310673D02*
X346000Y310173D01*
G01X346500Y311673D02*
Y310673D01*
G01X346000Y312173D02*
X346500Y311673D01*
G01X337600Y312173D02*
X346000D01*
G01X337100Y312673D02*
X337600Y312173D01*
G01X337100Y313673D02*
Y312673D01*
G01X337600Y314173D02*
X337100Y313673D01*
G01X340700Y314173D02*
X337600D01*
G01X341200Y314673D02*
X340700Y314173D01*
G01X341200Y315673D02*
Y314673D01*
G01X340700Y316173D02*
X341200Y315673D01*
G01X337200Y316173D02*
X340700D01*
G01X336700Y316673D02*
X337200Y316173D01*
G01X336700Y317673D02*
Y316673D01*
G01X337200Y318173D02*
X336700Y317673D01*
G01X342500Y318173D02*
X337200D01*
G01X343000Y318673D02*
X342500Y318173D01*
G01X343000Y319673D02*
Y318673D01*
G01X342500Y320173D02*
X343000Y319673D01*
G01X336800Y320173D02*
X342500D01*
G01X336300Y320673D02*
X336800Y320173D01*
G01X336300Y321673D02*
Y320673D01*
G01X336800Y322173D02*
X336300Y321673D01*
G01X342500Y322173D02*
X336800D01*
G01X343000Y322673D02*
X342500Y322173D01*
G01X343000Y323673D02*
Y322673D01*
G01X342500Y324173D02*
X343000Y323673D01*
G01X336700Y324173D02*
X342500D01*
G01X336200Y324673D02*
X336700Y324173D01*
G01X336200Y325673D02*
Y324673D01*
G01X336700Y326173D02*
X336200Y325673D01*
G01X342700Y326173D02*
X336700D01*
G01X343200Y326673D02*
X342700Y326173D01*
G01X343200Y327673D02*
Y326673D01*
G01X342700Y328173D02*
X343200Y327673D01*
G01X336800Y328173D02*
X342700D01*
G01X336300Y328673D02*
X336800Y328173D01*
G01X336300Y329673D02*
Y328673D01*
G01X336800Y330173D02*
X336300Y329673D01*
G01X342500Y330173D02*
X336800D01*
G01X343000Y330673D02*
X342500Y330173D01*
G01X343000Y331673D02*
Y330673D01*
G01X342500Y332173D02*
X343000Y331673D01*
G01X335900Y332173D02*
X342500D01*
G01X335400Y332673D02*
X335900Y332173D01*
G01X335400Y333673D02*
Y332673D01*
G01X335900Y334173D02*
X335400Y333673D01*
G01X342300Y334173D02*
X335900D01*
G01X342800Y334673D02*
X342300Y334173D01*
G01X342800Y335673D02*
Y334673D01*
G01X342300Y336173D02*
X342800Y335673D01*
G01X336627Y336173D02*
X342300D01*
G01X335400Y337400D02*
X336627Y336173D01*
G01X381133Y311746D02*
X380234Y310847D01*
G01X381133Y314895D02*
Y311746D01*
G01X386159Y323393D02*
Y327300D01*
G01X381133Y318367D02*
X386159Y323393D01*
G01X381133Y314895D02*
Y318367D01*
G01X386159Y327300D02*
Y337080D01*
G01X331026Y302441D02*
X331765Y301702D01*
G01X331026Y303354D02*
Y302441D01*
G01X340375Y355800D02*
Y365944D01*
G01X340875Y355300D02*
X340375Y355800D01*
G01X342800Y355300D02*
X340875D01*
G01X343300Y355800D02*
X342800Y355300D01*
G01X343300Y366200D02*
Y355800D01*
G01X346200D02*
Y366200D01*
G01X346700Y355300D02*
X346200Y355800D01*
G01X347800Y355300D02*
X346700D01*
G01X348300Y355800D02*
X347800Y355300D01*
G01X348300Y376100D02*
Y355800D01*
G01X350500Y360600D02*
Y376100D01*
G01X351000Y360100D02*
X350500Y360600D01*
G01X352000Y360100D02*
X351000D01*
G01X352500Y360600D02*
X352000Y360100D01*
G01X352500Y378700D02*
Y360600D01*
G01X329228Y301393D02*
X329795Y300826D01*
G01X329228Y313828D02*
Y301393D01*
G01X329364Y313964D02*
X329228Y313828D01*
G01X329364Y316949D02*
Y313964D01*
G01X328100Y319800D02*
Y331300D01*
G01X327100Y318800D02*
X328100Y319800D01*
G01X327100Y317044D02*
Y318800D01*
G01X326600Y316544D02*
X327100Y317044D01*
G01Y314044D02*
X326600Y314544D01*
G01X327100Y313044D02*
Y314044D01*
G01X326600Y312544D02*
X327100Y313044D01*
G01Y310044D02*
X326600Y310544D01*
G01X327100Y303695D02*
Y310044D01*
G01X327825Y302970D02*
X327100Y303695D01*
G01X329670Y353099D02*
Y368002D01*
G01X328623Y352052D02*
X329670Y353099D01*
G01X327917Y352052D02*
X328623D01*
G01X326289Y353681D02*
X327917Y352052D01*
G01X325583Y353681D02*
X326289D01*
G01X324874Y352972D02*
X325583Y353681D01*
G01X324874Y352266D02*
Y352972D01*
G01X326502Y350637D02*
X324874Y352266D01*
G01X326502Y349931D02*
Y350637D01*
G01X325400Y348829D02*
X326502Y349931D01*
G01X325400Y340624D02*
Y348829D01*
G01X325900Y340124D02*
X325400Y340624D01*
G01X327700Y340124D02*
X325900D01*
G01X328200Y339624D02*
X327700Y340124D01*
G01X328200Y338624D02*
Y339624D01*
G01X327700Y338124D02*
X328200Y338624D01*
G01X325900Y338124D02*
X327700D01*
G01X325400Y337624D02*
X325900Y338124D01*
G01X325400Y336624D02*
Y337624D01*
G01X325900Y336124D02*
X325400Y336624D01*
G01X327700Y336124D02*
X325900D01*
G01X328200Y335624D02*
X327700Y336124D01*
G01X328200Y334624D02*
Y335624D01*
G01X327700Y334124D02*
X328200Y334624D01*
G01X325900Y334124D02*
X327700D01*
G01X325400Y333624D02*
X325900Y334124D01*
G01X325400Y328600D02*
Y333624D01*
G01X387616Y382384D02*
X360000Y410000D01*
G01X339640Y384140D02*
X344000Y388500D01*
G01X339640Y373350D02*
Y384140D01*
G01X366200Y378400D02*
X365700Y377900D01*
G01X368300Y378400D02*
X366200D01*
G01X368800Y377900D02*
X368300Y378400D01*
G01X329795Y370706D02*
X331670Y368831D01*
G01X329795Y373350D02*
Y370706D01*
G01X331765Y373350D02*
Y386535D01*
G01X332040Y412340D02*
X335133D01*
G01X370160D02*
X335133D01*
G01X393316Y389184D02*
X370160Y412340D01*
G01X335700Y369817D02*
Y373350D01*
G01X335670Y369787D02*
X335700Y369817D01*
G01X335670Y367378D02*
Y369787D01*
G01X336170Y366878D02*
X335670Y367378D01*
G01X337800Y366878D02*
X336170D01*
G01X338300Y366378D02*
X337800Y366878D01*
G01X338300Y365378D02*
Y366378D01*
G01X337800Y364878D02*
X338300Y365378D01*
G01X336170Y364878D02*
X337800D01*
G01X335670Y364378D02*
X336170Y364878D01*
G01X335670Y363378D02*
Y364378D01*
G01X336170Y362878D02*
X335670Y363378D01*
G01X337800Y362878D02*
X336170D01*
G01X338300Y362378D02*
X337800Y362878D01*
G01X355000Y381600D02*
X354500Y381100D01*
G01X357900Y381600D02*
X355000D01*
G01X358400Y381100D02*
X357900Y381600D01*
G01X325860Y368983D02*
Y373350D01*
G01X327670Y367173D02*
X325860Y368983D01*
G01X333730Y370389D02*
Y373350D01*
G01X333670Y370329D02*
X333730Y370389D01*
G01X363200Y389724D02*
X363700Y389224D01*
G01X353200Y389724D02*
X363200D01*
G01X352700Y389224D02*
X353200Y389724D01*
G01X352700Y388224D02*
Y389224D01*
G01X353200Y387724D02*
X352700Y388224D01*
G01X359900Y387724D02*
X353200D01*
G01X360400Y387224D02*
X359900Y387724D01*
G01X360400Y386224D02*
Y387224D01*
G01X359900Y385724D02*
X360400Y386224D01*
G01X353200Y385724D02*
X359900D01*
G01X352700Y385224D02*
X353200Y385724D01*
G01X352700Y384224D02*
Y385224D01*
G01X353200Y383724D02*
X352700Y384224D01*
G01X359900Y383724D02*
X353200D01*
G01X360400Y383224D02*
X359900Y383724D01*
G01X343800Y366700D02*
X343300Y366200D01*
G01X345700Y366700D02*
X343800D01*
G01X346200Y366200D02*
X345700Y366700D01*
G01X348800Y376600D02*
X348300Y376100D01*
G01X350000Y376600D02*
X348800D01*
G01X350500Y376100D02*
X350000Y376600D01*
G01X352000Y379200D02*
X352500Y378700D01*
G01X346500Y379200D02*
X352000D01*
G01X346000Y378700D02*
X346500Y379200D01*
G01X346000Y369400D02*
Y378700D01*
G01X345500Y368900D02*
X346000Y369400D01*
G01X338170Y368900D02*
X345500D01*
G01X337670Y369400D02*
X338170Y368900D01*
G01X337670Y373350D02*
Y369400D01*
G01X327825Y369847D02*
Y373350D01*
G01X329670Y368002D02*
X327825Y369847D01*
G01X435100Y293247D02*
Y312076D01*
G01X437008Y291339D02*
X435100Y293247D01*
G01X431101Y301181D02*
X429134Y299214D01*
G01X446859Y293298D02*
X448818Y291339D01*
G01X442908Y293298D02*
X446859D01*
G01X429134Y295275D02*
X431102Y293307D01*
G01X429134Y295277D02*
Y295275D01*
G01X448819Y287403D02*
X450800Y289384D01*
G01X421260Y295277D02*
X419292Y297245D01*
G01X407484Y262952D02*
X402708D01*
G01X408471D02*
X407484D01*
G01X409449Y261974D02*
X408471Y262952D01*
G01X409449Y259843D02*
Y261974D01*
G01X425197Y299213D02*
X423228Y301182D01*
G01X423221Y293300D02*
X425197Y295276D01*
G01X427166Y297245D02*
Y311677D01*
G01Y289371D02*
X429134Y287403D01*
G01X427166Y297245D02*
Y289371D01*
G01X418874Y301600D02*
X421260Y299214D01*
G01X443272Y299043D02*
Y301181D01*
G01X441568Y297339D02*
X443272Y299043D01*
G01X438882Y297339D02*
X441568D01*
G01X437008Y299213D02*
X438882Y297339D01*
G01X417323Y311023D02*
X419291Y309055D01*
G01X417323Y311024D02*
Y311023D01*
G01X427165Y320427D02*
Y316929D01*
G01X428227Y321489D02*
X427165Y320427D01*
G01X428227Y328438D02*
Y321489D01*
G01X427500Y329165D02*
X428227Y328438D01*
G01X427500Y330650D02*
Y329165D01*
G01X427166Y316929D02*
X429134Y314961D01*
G01X427165Y316929D02*
X427166D01*
G01X425737Y327992D02*
Y325715D01*
G01X424500Y329229D02*
X425737Y327992D01*
G01X424500Y343310D02*
Y329229D01*
G01X423260Y344550D02*
X424500Y343310D01*
G01X421500Y344550D02*
X423260D01*
G01X425737Y319438D02*
X425197Y318898D01*
G01X425737Y325715D02*
Y319438D01*
G01X444100Y344554D02*
Y345000D01*
G01X440740Y341194D02*
X444100Y344554D01*
G01X440740Y339742D02*
Y341194D01*
G01X442150Y338332D02*
X440740Y339742D01*
G01X442150Y335309D02*
Y338332D01*
G01X440803Y333962D02*
X442150Y335309D01*
G01X440803Y325620D02*
Y333962D01*
G01X439335Y324152D02*
X440803Y325620D01*
G01X439335Y314496D02*
Y324152D01*
G01X438021Y313182D02*
X439335Y314496D01*
G01X436206Y313182D02*
X438021D01*
G01X435100Y312076D02*
X436206Y313182D01*
G01X411836Y329086D02*
X413000Y330250D01*
G01X411836Y326129D02*
Y329086D01*
G01X413115Y324850D02*
X411836Y326129D01*
G01X413115Y323215D02*
Y324850D01*
G01X411736Y321836D02*
X413115Y323215D01*
G01X411736Y313164D02*
Y321836D01*
G01X413386Y311514D02*
X411736Y313164D01*
G01X413386Y311025D02*
Y311514D01*
G01X438977Y305118D02*
X442913D01*
G01X437008Y307087D02*
X438977Y305118D01*
G01X429134Y307039D02*
X431105Y309010D01*
G01X429134Y303151D02*
Y307039D01*
G01X431102Y301181D02*
X431101D01*
G01X435039Y319123D02*
Y316929D01*
G01X436894Y320978D02*
X435039Y319123D01*
G01X436894Y329174D02*
Y320978D01*
G01X436950Y329230D02*
X436894Y329174D01*
G01X436950Y335060D02*
Y329230D01*
G01X437251Y335361D02*
X436950Y335060D01*
G01X437251Y337639D02*
Y335361D01*
G01X436894Y337996D02*
X437251Y337639D01*
G01X436894Y351183D02*
Y337996D01*
G01X436736Y351341D02*
X436894Y351183D01*
G01X435039Y314564D02*
Y316929D01*
G01X433049Y312574D02*
X435039Y314564D01*
G01X432428Y312574D02*
X433049D01*
G01X432416Y312562D02*
X432428Y312574D01*
G01X430672Y312562D02*
X432416D01*
G01X429134Y311024D02*
X430672Y312562D01*
G01X444882Y319935D02*
Y318898D01*
G01X446700Y321753D02*
X444882Y319935D01*
G01X446700Y325400D02*
Y321753D01*
G01X448300Y327000D02*
X446700Y325400D01*
G01X448300Y329650D02*
Y327000D01*
G01X449400Y330750D02*
X448300Y329650D01*
G01X401700Y337350D02*
Y340950D01*
G01X391900Y344150D02*
X396000D01*
G01X400771D02*
X396000D01*
G01X401700Y343221D02*
X400771Y344150D01*
G01X401700Y340950D02*
Y343221D01*
G01X423228Y301182D02*
Y305118D01*
G01Y311249D02*
Y305118D01*
G01X421494Y312983D02*
X423228Y311249D01*
G01X421045Y312983D02*
X421494D01*
G01X419097Y314931D02*
X421045Y312983D01*
G01X419097Y315380D02*
Y314931D01*
G01X417966Y316511D02*
X419097Y315380D01*
G01X417517Y316511D02*
X417966D01*
G01X415173Y318855D02*
X417517Y316511D01*
G01X415173Y337407D02*
Y318855D01*
G01X413400Y339180D02*
X415173Y337407D01*
G01X413400Y340550D02*
Y339180D01*
G01X418874Y305537D02*
X421260Y303151D01*
G01X415863Y305537D02*
X418874D01*
G01X415200Y306200D02*
X415863Y305537D01*
G01X415200Y308200D02*
Y306200D01*
G01X414300Y309100D02*
X415200Y308200D01*
G01X412700Y309100D02*
X414300D01*
G01X411800Y310000D02*
X412700Y309100D01*
G01X411800Y311400D02*
Y310000D01*
G01X410200Y313000D02*
X411800Y311400D01*
G01X407900Y313000D02*
X410200D01*
G01X407300Y313600D02*
X407900Y313000D01*
G01X407300Y327430D02*
Y313600D01*
G01X406070Y328660D02*
X407300Y327430D01*
G01X406070Y333730D02*
Y328660D01*
G01X407970Y335630D02*
X406070Y333730D01*
G01X409100Y336760D02*
X407970Y335630D01*
G01X409100Y340550D02*
Y336760D01*
G01X407015Y340550D02*
X405783Y339318D01*
G01X409100Y340550D02*
X407015D01*
G01X437008Y311023D02*
X438976Y309055D01*
G01X437008Y311024D02*
Y311023D01*
G01X448300Y337500D02*
X449300D01*
G01X447300Y338500D02*
X448300Y337500D01*
G01X447300Y340850D02*
Y338500D01*
G01X447854Y323304D02*
X450200Y325650D01*
G01X447854Y321054D02*
Y323304D01*
G01X446500Y319700D02*
X447854Y321054D01*
G01X446500Y313400D02*
Y319700D01*
G01X447000Y312900D02*
X446500Y313400D01*
G01X452100Y312900D02*
X447000D01*
G01X430250Y341300D02*
X427500Y344050D01*
G01X430250Y335381D02*
Y341300D01*
G01X433000Y332631D02*
X430250Y335381D01*
G01X433000Y330000D02*
Y332631D01*
G01X431496Y328496D02*
X433000Y330000D01*
G01X431496Y326673D02*
Y328496D01*
G01X431203Y326380D02*
X431496Y326673D01*
G01X429134Y319853D02*
Y318898D01*
G01X429618Y320337D02*
X429134Y319853D01*
G01X429618Y324795D02*
Y320337D01*
G01X431203Y326380D02*
X429618Y324795D01*
G01X430633Y344350D02*
X432900D01*
G01X430333Y344050D02*
X430633Y344350D01*
G01X427500Y344050D02*
X430333D01*
G01X417400Y329500D02*
Y340550D01*
G01X419339Y327561D02*
X417400Y329500D01*
G01X419339Y318626D02*
Y327561D01*
G01X420617Y317348D02*
X419339Y318626D01*
G01X421066Y317348D02*
X420617D01*
G01X422810Y315604D02*
X421066Y317348D01*
G01X422810Y315155D02*
Y315604D01*
G01X424554Y313411D02*
X422810Y315155D01*
G01X425432Y313411D02*
X424554D01*
G01X427166Y311677D02*
X425432Y313411D01*
G01X437008Y303149D02*
X438976Y301181D01*
G01X437008Y303150D02*
Y303149D01*
G01X430940Y317092D02*
X433071Y314961D01*
G01X430940Y322507D02*
Y317092D01*
G01X435200Y326767D02*
X430940Y322507D01*
G01X435200Y330550D02*
Y326767D01*
G01X434000Y319827D02*
Y322200D01*
G01X433071Y318898D02*
X434000Y319827D01*
G01X423229Y316929D02*
Y320867D01*
G01X425197Y314961D02*
X423229Y316929D01*
G01Y328014D02*
Y320867D01*
G01X421500Y329743D02*
X423229Y328014D01*
G01X421500Y330750D02*
Y329743D01*
G01X412400Y301600D02*
X418874D01*
G01X411500Y302500D02*
X412400Y301600D01*
G01X411500Y308100D02*
Y302500D01*
G01X410500Y309100D02*
X411500Y308100D01*
G01X405200Y309100D02*
X410500D01*
G01X403700Y310600D02*
X405200Y309100D01*
G01X403700Y329410D02*
Y310600D01*
G01X401680Y331430D02*
X403700Y329410D01*
G01X390550Y329732D02*
X392453Y331635D01*
G01X390550Y326820D02*
Y329732D01*
G01X394638Y333820D02*
X392453Y331635D01*
G01X399290Y333820D02*
X394638D01*
G01X401680Y331430D02*
X399290Y333820D01*
G01X442913Y323413D02*
Y320866D01*
G01X444600Y325100D02*
X442913Y323413D01*
G01X444600Y329950D02*
Y325100D01*
G01X445400Y330750D02*
X444600Y329950D01*
G01X442913Y310280D02*
Y320866D01*
G01X443719Y309474D02*
X442913Y310280D01*
G01X445725Y309474D02*
X443719D01*
G01X447000Y308199D02*
X445725Y309474D01*
G01X447000Y304909D02*
Y308199D01*
G01X443272Y301181D02*
X447000Y304909D01*
G01X433839Y382384D02*
X387616D01*
G01X457599Y406144D02*
X433839Y382384D01*
G01X431163Y389184D02*
X393316D01*
G01X445000Y403021D02*
X431163Y389184D01*
G01X445000Y422000D02*
Y403021D01*
G01X505776Y197197D02*
Y198689D01*
G01X503379Y194800D02*
X505776Y197197D01*
G01X501950Y194800D02*
X503379D01*
G01X505776Y198949D02*
Y198689D01*
G01X503937Y200788D02*
X505776Y198949D01*
G01X498506Y200788D02*
X496828Y199110D01*
G01X500000Y200788D02*
X498506D01*
G01X496828Y196422D02*
Y199110D01*
G01X498450Y194800D02*
X496828Y196422D01*
G01X460630Y300833D02*
Y299213D01*
G01X466535Y301183D02*
X468504Y299214D01*
G01X475905Y291812D02*
Y305405D01*
G01X476378Y291339D02*
X475905Y291812D01*
G01X450800Y289384D02*
Y303801D01*
G01X456693Y292907D02*
Y291339D01*
G01X454724Y294876D02*
X456693Y292907D01*
G01X454724Y301181D02*
Y294876D01*
G01X484392Y300317D02*
Y298681D01*
G01Y295417D02*
X484252Y295277D01*
G01X484392Y298681D02*
Y295417D01*
G01X474400Y293298D02*
X472441Y291339D01*
G01X474400Y296900D02*
Y293298D01*
G01X473700Y297600D02*
X474400Y296900D01*
G01X471041Y297600D02*
X473700D01*
G01X470541Y298100D02*
X471041Y297600D01*
G01X470541Y307421D02*
Y298100D01*
G01X477955Y296160D02*
Y301006D01*
G01X478839Y295276D02*
X477955Y296160D01*
G01X480315Y295276D02*
X478839D01*
G01X469700Y311024D02*
X468504D01*
G01X470324Y310400D02*
X469700Y311024D01*
G01X472600Y310400D02*
X470324D01*
G01X501850Y331350D02*
X506700Y336200D01*
G01X494511Y331350D02*
X501850D01*
G01X490142Y326981D02*
X494511Y331350D01*
G01X490142Y321803D02*
Y326981D01*
G01X488189Y319850D02*
X490142Y321803D01*
G01X488189Y311024D02*
Y319850D01*
G01X509517Y339017D02*
Y341796D01*
G01X506700Y336200D02*
X509517Y339017D01*
G01X462663Y302866D02*
X460630Y300833D01*
G01X462663Y323248D02*
Y302866D01*
G01X466438Y339188D02*
X468000Y340750D01*
G01X466438Y336831D02*
Y339188D01*
G01X464789Y335182D02*
X466438Y336831D01*
G01X464789Y327073D02*
Y335182D01*
G01X462663Y324947D02*
X464789Y327073D01*
G01X462663Y323248D02*
Y324947D01*
G01X509100Y312250D02*
X507874Y311024D01*
G01X511215Y312250D02*
X509100D01*
G01X510601Y311250D02*
X511630D01*
G01X508464Y309113D02*
X510601Y311250D01*
G01X505963Y309113D02*
X508464D01*
G01X503937Y307087D02*
X505963Y309113D01*
G01X504704Y330204D02*
X513517Y339017D01*
G01X496304Y330204D02*
X504704D01*
G01X493676Y327576D02*
X496304Y330204D01*
G01X493676Y321226D02*
Y327576D01*
G01X492950Y320500D02*
X493676Y321226D01*
G01X490826Y320500D02*
X492950D01*
G01X489576Y319250D02*
X490826Y320500D01*
G01X489576Y313500D02*
Y319250D01*
G01X490158Y312918D02*
X489576Y313500D01*
G01X490158Y309055D02*
Y312918D01*
G01X490157Y309055D02*
X490158D01*
G01X488189Y307087D02*
X490157Y309055D01*
G01X466535Y305118D02*
Y301183D01*
G01X510000Y348638D02*
X510138Y348500D01*
G01X510000Y351550D02*
Y348638D01*
G01X506350Y328950D02*
X517517Y340117D01*
G01X501096Y328950D02*
X506350D01*
G01X500300Y328154D02*
X501096Y328950D01*
G01X492126Y312768D02*
Y311024D01*
G01X490576Y314318D02*
X492126Y312768D01*
G01X490576Y315604D02*
Y314318D01*
G01X491522Y316550D02*
X490576Y315604D01*
G01X491971Y316550D02*
X491522D01*
G01X494075Y318654D02*
X491971Y316550D01*
G01X494075Y319875D02*
Y318654D01*
G01X494800Y320600D02*
X494075Y319875D01*
G01X494800Y326717D02*
Y320600D01*
G01X496237Y328154D02*
X494800Y326717D01*
G01X500300Y328154D02*
X496237D01*
G01X469031Y344250D02*
X468000D01*
G01X471749Y346968D02*
X469031Y344250D01*
G01X471749Y349768D02*
Y346968D01*
G01X472000Y350019D02*
X471749Y349768D01*
G01X472000Y350750D02*
Y350019D01*
G01X467900Y349100D02*
Y350750D01*
G01X468500Y348500D02*
X467900Y349100D01*
G01X468500Y347500D02*
Y348500D01*
G01X471450Y351300D02*
X472000Y350750D01*
G01X468450Y351300D02*
X471450D01*
G01X467900Y350750D02*
X468450Y351300D01*
G01X496063Y320650D02*
Y318898D01*
G01X497550Y322137D02*
X496063Y320650D01*
G01X497550Y324150D02*
Y322137D01*
G01X506000Y348762D02*
X506262Y348500D01*
G01X506000Y351550D02*
Y348762D01*
G01X494195Y349945D02*
X496100Y351850D01*
G01X494195Y340124D02*
Y349945D01*
G01X483050Y328979D02*
X494195Y340124D01*
G01X483050Y326950D02*
Y328979D01*
G01X481100Y325000D02*
X483050Y326950D01*
G01X479500Y325000D02*
X481100D01*
G01X478300Y323800D02*
X479500Y325000D01*
G01X478300Y322150D02*
Y323800D01*
G01X479600Y320850D02*
X478300Y322150D01*
G01X479600Y310300D02*
Y320850D01*
G01Y309100D02*
Y310300D01*
G01X475905Y305405D02*
X479600Y309100D01*
G01X486594Y359605D02*
Y359195D01*
G01X487250Y360261D02*
X486594Y359605D01*
G01X487250Y364840D02*
Y360261D01*
G01X482745Y350406D02*
X486873D01*
G01X481856Y351295D02*
X482745Y350406D01*
G01X481856Y352656D02*
Y351295D01*
G01X482838Y354873D02*
X486594D01*
G01X481856Y353891D02*
X482838Y354873D01*
G01X481856Y352656D02*
Y353891D01*
G01X486594Y354873D02*
Y359195D01*
G01X452300Y336650D02*
Y337500D01*
G01X453050Y335900D02*
X452300Y336650D01*
G01X453750Y335900D02*
X453050D01*
G01X455800Y333850D02*
X453750Y335900D01*
G01X455800Y331400D02*
Y333850D01*
G01X454000Y329600D02*
X455800Y331400D01*
G01X454000Y322800D02*
Y329600D01*
G01X452450Y321250D02*
X454000Y322800D01*
G01X452450Y314884D02*
Y321250D01*
G01X454777Y312557D02*
X452450Y314884D01*
G01X454777Y306277D02*
Y312557D01*
G01X453500Y305000D02*
X454777Y306277D01*
G01X451999Y305000D02*
X453500D01*
G01X450800Y303801D02*
X451999Y305000D01*
G01X451300Y338500D02*
X452300Y337500D01*
G01X451300Y340850D02*
Y338500D01*
G01X491445Y346908D02*
Y342700D01*
G01X476378Y311978D02*
Y311024D01*
G01X477928Y313528D02*
X476378Y311978D01*
G01X477928Y320122D02*
Y313528D01*
G01X477300Y320750D02*
X477928Y320122D01*
G01X477300Y326089D02*
Y320750D01*
G01X491445Y340234D02*
X477300Y326089D01*
G01X491445Y342700D02*
Y340234D01*
G01X468257Y321783D02*
Y323578D01*
G01X470290Y319750D02*
X468257Y321783D01*
G01X470290Y317112D02*
Y319750D01*
G01X472441Y314961D02*
X470290Y317112D01*
G01X474550Y334900D02*
X476200D01*
G01X468257Y328607D02*
X474550Y334900D01*
G01X468257Y323578D02*
Y328607D01*
G01X476200Y336155D02*
Y334900D01*
G01X474577Y337778D02*
X476200Y336155D01*
G01X474577Y339415D02*
Y337778D01*
G01X454291Y351640D02*
Y356355D01*
G01Y349591D02*
Y351640D01*
G01X453400Y348700D02*
X454291Y349591D01*
G01X453400Y339400D02*
Y348700D01*
G01X454549Y338251D02*
X453400Y339400D01*
G01X454549Y336672D02*
Y338251D01*
G01X457150Y334071D02*
X454549Y336672D01*
G01X457150Y330650D02*
Y334071D01*
G01X456248Y329748D02*
X457150Y330650D01*
G01X456248Y323148D02*
Y329748D01*
G01X453650Y320550D02*
X456248Y323148D01*
G01X453650Y317150D02*
Y320550D01*
G01X455100Y315700D02*
X453650Y317150D01*
G01X455100Y313893D02*
Y315700D01*
G01X456286Y312707D02*
X455100Y313893D01*
G01X457773Y312707D02*
X456286D01*
G01X458752Y311728D02*
X457773Y312707D01*
G01X458752Y306076D02*
Y311728D01*
G01X457476Y304800D02*
X458752Y306076D01*
G01X455652Y304800D02*
X457476D01*
G01X454724Y303872D02*
X455652Y304800D01*
G01X454724Y301181D02*
Y303872D01*
G01X477900Y333229D02*
X475834Y331163D01*
G01X477900Y335451D02*
Y333229D01*
G01X479067Y336618D02*
X477900Y335451D01*
G01X481906Y336618D02*
X479067D01*
G01X482618Y337330D02*
X481906Y336618D01*
G01X482618Y339392D02*
Y337330D01*
G01X474508Y329837D02*
X475834Y331163D01*
G01X472463Y329837D02*
X474508D01*
G01X478618Y339392D02*
X482618D01*
G01X509424Y321913D02*
X516298Y328787D01*
G01X509424Y318255D02*
Y321913D01*
G01X508517Y317348D02*
X509424Y318255D01*
G01X506263Y317348D02*
X508517D01*
G01X504595Y315680D02*
X506263Y317348D01*
G01X503172Y315680D02*
X504595D01*
G01X500484Y312992D02*
X503172Y315680D01*
G01X498032Y312992D02*
X500484D01*
G01X498031D02*
X496063Y311024D01*
G01X498032Y312992D02*
X498031D01*
G01X486135Y302060D02*
X484392Y300317D01*
G01X486135Y304080D02*
Y302060D01*
G01X487325Y305270D02*
X486135Y304080D01*
G01X492772Y305270D02*
X487325D01*
G01X493870Y306368D02*
X492772Y305270D01*
G01X493870Y314961D02*
Y306368D01*
G01X496257Y317348D02*
X493870Y314961D01*
G01X496706Y317348D02*
X496257D01*
G01X497613Y318255D02*
X496706Y317348D01*
G01X497613Y318963D02*
Y318255D01*
G01X500700Y322050D02*
X497613Y318963D01*
G01X500700Y324598D02*
Y322050D01*
G01X503356Y327254D02*
X500700Y324598D01*
G01X507554Y327254D02*
X503356D01*
G01X521522Y341222D02*
X507554Y327254D01*
G01X468911Y309051D02*
X470541Y307421D01*
G01X467618Y309051D02*
X468911D01*
G01X466725Y309944D02*
X467618Y309051D01*
G01X466725Y320194D02*
Y309944D01*
G01X465883Y321036D02*
X466725Y320194D01*
G01X465883Y325851D02*
Y321036D01*
G01X466725Y326693D02*
X465883Y325851D01*
G01X466725Y331725D02*
Y326693D01*
G01X468500Y333500D02*
X466725Y331725D01*
G01X475990Y354350D02*
X477400D01*
G01X474500Y352860D02*
X475990Y354350D01*
G01X474500Y349690D02*
Y352860D01*
G01X473749Y348939D02*
X474500Y349690D01*
G01X473749Y346139D02*
Y348939D01*
G01X470200Y342590D02*
X473749Y346139D01*
G01X470200Y335200D02*
Y342590D01*
G01X468500Y333500D02*
X470200Y335200D01*
G01X452300Y327750D02*
X450200Y325650D01*
G01X452300Y329501D02*
Y327750D01*
G01X454551Y331752D02*
X452300Y329501D01*
G01X454551Y333224D02*
Y331752D01*
G01X452975Y334800D02*
X454551Y333224D01*
G01X452000Y334800D02*
X452975D01*
G01X449300Y337500D02*
X452000Y334800D01*
G01X452755Y312245D02*
X452100Y312900D01*
G01X452755Y307087D02*
Y312245D01*
G01X501227Y349411D02*
Y354336D01*
G01X502138Y348500D02*
X501227Y349411D01*
G01Y357231D02*
Y354336D01*
G01X502200Y358204D02*
X501227Y357231D01*
G01X502200Y360559D02*
Y358204D01*
G01X503937Y320537D02*
Y318898D01*
G01X515972Y332572D02*
X503937Y320537D01*
G01X497206Y340306D02*
Y341781D01*
G01X484750Y327850D02*
X497206Y340306D01*
G01X484750Y326300D02*
Y327850D01*
G01X482450Y324000D02*
X484750Y326300D01*
G01X482450Y322777D02*
Y324000D01*
G01X480702Y321029D02*
X482450Y322777D01*
G01X480702Y312297D02*
Y321029D01*
G01X481702Y311297D02*
X480702Y312297D01*
G01X481702Y309966D02*
Y311297D01*
G01X481865Y309803D02*
X481702Y309966D01*
G01X481865Y306444D02*
Y309803D01*
G01X480421Y305000D02*
X481865Y306444D01*
G01X479972Y305000D02*
X480421D01*
G01X477955Y302983D02*
X479972Y305000D01*
G01X477955Y301006D02*
Y302983D01*
G01X502387Y323244D02*
X503468Y324325D01*
G01X502387Y319017D02*
Y323244D01*
G01X500270Y316900D02*
X502387Y319017D01*
G01X498002Y316900D02*
X500270D01*
G01X496063Y314961D02*
X498002Y316900D01*
G01X473265Y319722D02*
Y322929D01*
G01X472441Y318898D02*
X473265Y319722D01*
G01X479640Y331675D02*
Y334674D01*
G01X473265Y325300D02*
X479640Y331675D01*
G01X473265Y322929D02*
Y325300D01*
G01X484252Y308831D02*
Y307087D01*
G01X482702Y310381D02*
X484252Y308831D01*
G01X482702Y311798D02*
Y310381D01*
G01X481702Y312798D02*
X482702Y311798D01*
G01X481702Y320302D02*
Y312798D01*
G01X484350Y322950D02*
X481702Y320302D01*
G01X484350Y324350D02*
Y322950D01*
G01X496000Y336000D02*
X484350Y324350D01*
G01X501281Y341281D02*
X496000Y336000D01*
G01X501281Y341761D02*
Y341281D01*
G01X484252Y304894D02*
Y303150D01*
G01X485802Y306444D02*
X484252Y304894D01*
G01X485802Y311667D02*
Y306444D01*
G01X484721Y312748D02*
X485802Y311667D01*
G01X484272Y312748D02*
X484721D01*
G01X482702Y314318D02*
X484272Y312748D01*
G01X482702Y319541D02*
Y314318D01*
G01X488600Y325439D02*
X482702Y319541D01*
G01X488600Y326854D02*
Y325439D01*
G01X494651Y332905D02*
X488600Y326854D01*
G01X498305Y332905D02*
X494651D01*
G01X501400Y336000D02*
X498305Y332905D01*
G01X505379Y339979D02*
Y341761D01*
G01X501400Y336000D02*
X505379Y339979D01*
G01X510800Y313250D02*
X514898Y317348D01*
G01X503757Y313250D02*
X510800D01*
G01X502035Y311528D02*
X503757Y313250D01*
G01X502035Y309123D02*
Y311528D01*
G01X500000Y307088D02*
X502035Y309123D01*
G01X456693Y315906D02*
Y314961D01*
G01X454943Y317656D02*
X456693Y315906D01*
G01X454943Y319943D02*
Y317656D01*
G01X458550Y323550D02*
X454943Y319943D01*
G01X458550Y338141D02*
Y323550D01*
G01X460000Y339591D02*
X458550Y338141D01*
G01X460000Y340750D02*
Y339591D01*
G01X455900Y339729D02*
Y340750D01*
G01X456549Y339080D02*
X455900Y339729D01*
G01X456549Y337501D02*
Y339080D01*
G01X456550Y337500D02*
X456549Y337501D01*
G01X455900Y340750D02*
X460000D01*
G01X474800Y309446D02*
X472441Y307087D01*
G01X474800Y314452D02*
Y309446D01*
G01X474210Y315042D02*
X474800Y314452D01*
G01X474210Y316992D02*
Y315042D01*
G01X486873Y338805D02*
Y346906D01*
G01X481132Y333064D02*
X486873Y338805D01*
G01X481132Y331336D02*
Y333064D01*
G01X475491Y325695D02*
X481132Y331336D01*
G01X475491Y320522D02*
Y325695D01*
G01X474210Y319241D02*
X475491Y320522D01*
G01X474210Y316992D02*
Y319241D01*
G01X456693Y319493D02*
Y318898D01*
G01X459874Y322674D02*
X456693Y319493D01*
G01X459874Y329226D02*
Y322674D01*
G01X462203Y331555D02*
X459874Y329226D01*
G01X462203Y334497D02*
Y331555D01*
G01X460800Y335900D02*
X462203Y334497D01*
G01X460800Y337562D02*
Y335900D01*
G01X463988Y340750D02*
X460800Y337562D01*
G01X464000Y340750D02*
X463988D01*
G01X506050Y320550D02*
X515500Y330000D01*
G01X506050Y318550D02*
Y320550D01*
G01X504180Y316680D02*
X506050Y318550D01*
G01X501720Y316680D02*
X504180D01*
G01X500001Y314961D02*
X501720Y316680D01*
G01X488900Y371800D02*
X489500Y371200D01*
G01X481750Y371800D02*
X488900D01*
G01X457599Y419642D02*
Y406144D01*
G01X510700Y367309D02*
X513237D01*
G01X489600Y367190D02*
X487250Y364840D01*
G01X489600Y367209D02*
Y367190D01*
G01X508950Y365059D02*
X512160D01*
G01X506700Y367309D02*
X508950Y365059D01*
G01X478350Y367500D02*
Y363400D01*
G01X474200Y367500D02*
X478350D01*
G01X495050Y368350D02*
Y373662D01*
G01Y377685D02*
X496300Y378935D01*
G01X495050Y373662D02*
Y377685D01*
G01X540200Y351350D02*
Y348300D01*
G01X514778Y315813D02*
X511215Y312250D01*
G01X516576Y315813D02*
X514778D01*
G01X519201Y318438D02*
X516576Y315813D01*
G01X519201Y321547D02*
Y318438D01*
G01X523254Y325600D02*
X519201Y321547D01*
G01X537116Y325600D02*
X523254D01*
G01X541747Y330231D02*
X537116Y325600D01*
G01X541747Y331715D02*
Y330231D01*
G01X543290Y331715D02*
X541747D01*
G01X544497Y332922D02*
X543290Y331715D01*
G01X544497Y338536D02*
Y332922D01*
G01X540686Y342347D02*
X544497Y338536D01*
G01X539446Y342347D02*
X540686D01*
G01X546533Y331682D02*
X547908D01*
G01X538451Y323600D02*
X546533Y331682D01*
G01X522669Y323600D02*
X538451D01*
G01X520600Y321531D02*
X522669Y323600D01*
G01X520600Y317735D02*
Y321531D01*
G01X517678Y314813D02*
X520600Y317735D01*
G01X515193Y314813D02*
X517678D01*
G01X511630Y311250D02*
X515193Y314813D01*
G01X550712Y334486D02*
X547908Y331682D01*
G01X550712Y337959D02*
Y334486D01*
G01X550200Y338471D02*
X550712Y337959D01*
G01X550200Y339926D02*
Y338471D01*
G01X547927Y342199D02*
X550200Y339926D01*
G01X513517Y339017D02*
Y341796D01*
G01X522500Y358046D02*
Y355750D01*
G01X513237Y367309D02*
X522500Y358046D01*
G01X517517Y340117D02*
Y341796D01*
G01X545200Y349200D02*
X546100Y348300D01*
G01X545200Y351350D02*
Y349200D01*
G01X558000Y343850D02*
X557500Y343350D01*
G01X558000Y348250D02*
Y343850D01*
G01X556800Y342650D02*
X557500Y343350D01*
G01X556800Y339300D02*
Y342650D01*
G01X552200Y343200D02*
X552100Y343300D01*
G01X552200Y339300D02*
Y343200D01*
G01X554000Y345200D02*
X552100Y343300D01*
G01X554000Y348250D02*
Y345200D01*
G01X518500Y358719D02*
Y355750D01*
G01X512160Y365059D02*
X518500Y358719D01*
G01X529947Y330764D02*
Y331750D01*
G01X528783Y329600D02*
X529947Y330764D01*
G01X521354Y329600D02*
X528783D01*
G01X520541Y328787D02*
X521354Y329600D01*
G01X516298Y328787D02*
X520541D01*
G01X529197Y332500D02*
X529947Y331750D01*
G01X522321Y332500D02*
X529197D01*
G01X521914Y332907D02*
X522321Y332500D01*
G01X521522Y341796D02*
Y341222D01*
G01X549200Y349200D02*
X550100Y348300D01*
G01X549200Y351350D02*
Y349200D01*
G01X516194Y332643D02*
Y332572D01*
G01X522425Y338874D02*
X516194Y332643D01*
G01X524174Y338874D02*
X522425D01*
G01X525522Y340222D02*
X524174Y338874D01*
G01X525522Y341796D02*
Y340222D01*
G01X516194Y332572D02*
X515972D01*
G01X533947Y329246D02*
Y331750D01*
G01X532301Y327600D02*
X533947Y329246D01*
G01X522553Y327600D02*
X532301D01*
G01X518200Y323247D02*
X522553Y327600D01*
G01X518200Y319088D02*
Y323247D01*
G01X516460Y317348D02*
X518200Y319088D01*
G01X514898Y317348D02*
X516460D01*
G01X536697Y339813D02*
X534100Y342410D01*
G01X536697Y336013D02*
Y339813D01*
G01X535968Y335284D02*
X536697Y336013D01*
G01X535968Y333771D02*
Y335284D01*
G01X533947Y331750D02*
X535968Y333771D01*
G01X536200Y351350D02*
Y348300D01*
G01X521500Y335500D02*
X524500D01*
G01X518945Y332945D02*
X521500Y335500D01*
G01X518945Y332098D02*
Y332945D01*
G01X516847Y330000D02*
X518945Y332098D01*
G01X515500Y330000D02*
X516847D01*
G01X529622Y340022D02*
Y341796D01*
G01X525100Y335500D02*
X529622Y340022D01*
G01X524500Y335500D02*
X525100D01*
G01X533578Y485100D02*
X529450D01*
G01X538308Y489830D02*
X533578Y485100D01*
G01X566489Y461086D02*
Y461261D01*
G01X562983Y457580D02*
X566489Y461086D01*
G01X562460Y457580D02*
X562983D01*
G01X559165Y466665D02*
X562855D01*
G01X557750Y465250D02*
X559165Y466665D01*
G01X557750Y461260D02*
Y465250D01*
G01X561656Y461260D02*
X557750D01*
G01X561657Y461261D02*
X561656Y461260D01*
G01X561657Y461261D02*
X566489D01*
G01X530175Y481225D02*
X521950D01*
G01X532050Y479350D02*
X530175Y481225D01*
G01X532050Y476200D02*
Y479350D01*
G01X531850Y476000D02*
X532050Y476200D01*
G01X527700Y476000D02*
X531850D01*
G01X547812Y468557D02*
Y464771D01*
G01X548295Y469040D02*
X547812Y468557D01*
G01X548295Y471383D02*
Y469040D01*
G01Y473474D02*
Y471383D01*
G01X545745Y476024D02*
X548295Y473474D01*
G01X545745Y480090D02*
Y476024D01*
G01X553900Y471995D02*
X555355Y470540D01*
G01X553900Y478000D02*
Y471995D01*
G01X552050Y479850D02*
X553900Y478000D01*
G01X550100Y479850D02*
X552050D01*
G01X549860Y480090D02*
X550100Y479850D01*
G01X545745Y480090D02*
X549860D01*
G01X569400Y483400D02*
X574050D01*
G01X566800D02*
X569400D01*
G01X565300Y484900D02*
X566800Y483400D01*
G01X555550Y484900D02*
X565300D01*
G01X570583Y473239D02*
X569402Y472058D01*
G01X570583Y476488D02*
Y473239D01*
G01X565212Y472058D02*
X569402D01*
G01X562855Y474415D02*
X565212Y472058D01*
G01X540140Y489830D02*
X538308D01*
G01X541710Y489440D02*
X549400D01*
G01X541320Y489830D02*
X541710Y489440D01*
G01X540140Y489830D02*
X541320D01*
G01X550065Y488775D02*
X549400Y489440D01*
G01X563050Y488775D02*
X550065D01*
G01X633803Y27697D02*
Y27749D01*
G01X638683Y22817D02*
X633803Y27697D01*
G01X628474Y29539D02*
X626786Y31227D01*
G01X632013Y29539D02*
X628474D01*
G01X633803Y27749D02*
X632013Y29539D01*
G01X633009Y62259D02*
X633000Y62250D01*
G01X637003Y62259D02*
X633009D01*
G01X632300Y154650D02*
X636630D01*
G01X633500Y172844D02*
X636844Y169500D01*
G01X633500Y187200D02*
Y172844D01*
G01X635150Y158150D02*
X638603Y161603D01*
G01X632300Y158150D02*
X635150D01*
G01X634794Y173884D02*
Y190106D01*
G01X637343Y171335D02*
X634794Y173884D01*
G01X624000Y196700D02*
X633500Y187200D01*
G01X624000Y203250D02*
Y196700D01*
G01X632000Y198800D02*
X631700Y198500D01*
G01X632000Y203250D02*
Y198800D01*
G01X636340Y193860D02*
X631700Y198500D01*
G01X628000Y200100D02*
X626400Y198500D01*
G01X628000Y203250D02*
Y200100D01*
G01X634794Y190106D02*
X626400Y198500D01*
G01X633481Y319984D02*
X623969D01*
G01X657705Y295760D02*
X633481Y319984D01*
G01X598216D02*
X597450Y320750D01*
G01X623969Y319984D02*
X598216D01*
G01X633838Y322456D02*
X611606D01*
G01X658534Y297760D02*
X633838Y322456D01*
G01X599744D02*
X597450Y324750D01*
G01X611606Y322456D02*
X599744D01*
G01X574050Y483400D02*
Y487900D01*
G01X659850Y40250D02*
Y42534D01*
G01X658116Y38516D02*
X659850Y40250D01*
G01X658116Y36660D02*
Y38516D01*
G01X659850Y42534D02*
Y46750D01*
G01X659843Y46743D02*
X659850Y46750D01*
G01X656051Y46743D02*
X659843D01*
G01X661600Y34100D02*
X658116D01*
G01X662200Y33500D02*
X661600Y34100D01*
G01X662200Y29748D02*
Y33500D01*
G01X658152Y25700D02*
X662200Y29748D01*
G01X647593Y25700D02*
X658152D01*
G01X644710Y22817D02*
X647593Y25700D01*
G01X644710Y22817D02*
X638683D01*
G01X664301Y49998D02*
Y51899D01*
G01Y40104D02*
Y49998D01*
G01X640683Y26317D02*
X639900Y27100D01*
G01X644710Y26317D02*
X640683D01*
G01X640416Y29759D02*
Y31609D01*
G01X639900Y29243D02*
X640416Y29759D01*
G01X639900Y27100D02*
Y29243D01*
G01X646280Y27887D02*
X644710Y26317D01*
G01X650876Y27887D02*
X646280D01*
G01X651616Y28627D02*
X650876Y27887D01*
G01X651616Y31540D02*
Y28627D01*
G01X641003Y62259D02*
X646000D01*
G01X637003D02*
X641003D01*
G01X653941D02*
X646000D01*
G01X664301Y51899D02*
X653941Y62259D01*
G01X640120Y156218D02*
X640775D01*
G01X638552Y154650D02*
X640120Y156218D01*
G01X636630Y154650D02*
X638552D01*
G01X696595Y127483D02*
X703073D01*
G01X693674Y130404D02*
X696595Y127483D01*
G01X693674Y132295D02*
Y130404D01*
G01X657480Y160477D02*
Y154330D01*
G01X656878Y161079D02*
X657480Y160477D01*
G01X656230Y161727D02*
X656878Y161079D01*
G01X653832Y161727D02*
X656230D01*
G01X647459Y168100D02*
X653832Y161727D01*
G01X642000Y168100D02*
X647459D01*
G01X640600Y169500D02*
X642000Y168100D01*
G01X636844Y169500D02*
X640600D01*
G01X638603Y161603D02*
X645729D01*
G01X648031Y160844D02*
Y157480D01*
G01X647272Y161603D02*
X648031Y160844D01*
G01X645729Y161603D02*
X647272D01*
G01X648031Y174581D02*
Y170078D01*
G01X650722Y177272D02*
X648031Y174581D01*
G01X648144Y166000D02*
X645250D01*
G01X650936Y163208D02*
X648144Y166000D01*
G01X650936Y160874D02*
Y163208D01*
G01X654330Y157480D02*
X650936Y160874D01*
G01X696824Y126483D02*
X695770Y125429D01*
G01X705223Y126483D02*
X696824D01*
G01X660629Y186271D02*
Y173227D01*
G01X637343Y174835D02*
X636340Y175838D01*
G01X646788Y175134D02*
X644882Y173228D01*
G01X646788Y176855D02*
Y175134D01*
G01X644882Y170078D02*
X637910Y177050D01*
G01X660629Y170818D02*
Y170078D01*
G01X658855Y172592D02*
X660629Y170818D01*
G01X658855Y186285D02*
Y172592D01*
G01X660084Y166929D02*
X657763D01*
G01X661644Y165369D02*
X660084Y166929D01*
G01X661644Y164498D02*
Y165369D01*
G01Y161644D02*
X660630Y160630D01*
G01X661644Y164498D02*
Y161644D01*
G01X651181Y154330D02*
X648035D01*
G01X639206Y178903D02*
X640509Y177600D01*
G01X639206Y188516D02*
Y178903D01*
G01X642300Y191610D02*
X639206Y188516D01*
G01X642300Y198500D02*
Y191610D01*
G01Y200950D02*
X640000Y203250D01*
G01X642300Y198500D02*
Y200950D01*
G01X694087Y199613D02*
X695275Y198425D01*
G01X694087Y201724D02*
Y199613D01*
G01X693500Y242254D02*
Y236469D01*
G01X692125Y200541D02*
Y198423D01*
G01X690207Y202459D02*
X692125Y200541D01*
G01X690207Y205597D02*
Y202459D01*
G01X650722Y185422D02*
Y183439D01*
G01X653300Y188000D02*
X650722Y185422D01*
G01X653300Y193200D02*
Y188000D01*
G01X648700Y197800D02*
X653300Y193200D01*
G01X648700Y199950D02*
Y197800D01*
G01X652000Y203250D02*
X648700Y199950D01*
G01X650722Y183439D02*
Y177272D01*
G01X643272Y183172D02*
X646000Y185900D01*
G01X643272Y177988D02*
Y183172D01*
G01X644882Y176378D02*
X643272Y177988D01*
G01X646000Y201250D02*
X644000Y203250D01*
G01X646000Y185900D02*
Y201250D01*
G01X690000Y236469D02*
X684696D01*
G01X680350Y237409D02*
Y241121D01*
G01X681290Y236469D02*
X680350Y237409D01*
G01X684696Y236469D02*
X681290D01*
G01X660000Y201302D02*
X657113Y198415D01*
G01X660000Y203250D02*
Y201302D01*
G01X655700Y191200D02*
X660629Y186271D01*
G01X655700Y197002D02*
Y191200D01*
G01X657113Y198415D02*
X655700Y197002D01*
G01X636340Y175838D02*
Y193860D01*
G01X646004Y177639D02*
X646788Y176855D01*
G01X646004Y179768D02*
Y177639D01*
G01X647067Y180831D02*
X646004Y179768D01*
G01X647067Y183267D02*
Y180831D01*
G01X648300Y184500D02*
X647067Y183267D01*
G01X648300Y187067D02*
Y184500D01*
G01X647067Y188300D02*
X648300Y187067D01*
G01X647067Y197367D02*
Y188300D01*
G01X647700Y198000D02*
X647067Y197367D01*
G01X647700Y200365D02*
Y198000D01*
G01X648000Y200665D02*
X647700Y200365D01*
G01X648000Y203250D02*
Y200665D01*
G01X636000Y199500D02*
X637000Y198500D01*
G01X636000Y203250D02*
Y199500D01*
G01X637910Y197590D02*
X637000Y198500D01*
G01X637910Y177050D02*
Y197590D01*
G01X654509Y190631D02*
X658855Y186285D01*
G01X654509Y195801D02*
Y190631D01*
G01X651722Y198588D02*
X654509Y195801D01*
G01X656000Y202866D02*
Y203250D01*
G01X651722Y198588D02*
X656000Y202866D01*
G01X680425Y208842D02*
Y205984D01*
G01X679452Y209815D02*
X680425Y208842D01*
G01Y202636D02*
Y205984D01*
G01X679334Y201545D02*
X680425Y202636D01*
G01X695600Y244354D02*
X693500Y242254D01*
G01X729020Y295760D02*
X657705D01*
G01X694216Y250155D02*
X700600Y256539D01*
G01X689468Y250155D02*
X694216D01*
G01X676638D02*
X689468D01*
G01X674989Y251804D02*
X676638Y250155D01*
G01X674989Y255684D02*
Y251804D01*
G01X728191Y297760D02*
X658534D01*
G01X680223Y274750D02*
X676875D01*
G01X683969Y278496D02*
X680223Y274750D01*
G01X690846Y278496D02*
X683969D01*
G01X695383Y273959D02*
X690846Y278496D01*
G01X695383Y266855D02*
Y273959D01*
G01X678739Y242732D02*
Y245084D01*
G01X680350Y241121D02*
X678739Y242732D01*
G01X672950Y282300D02*
X673000Y282250D01*
G01X672950Y288000D02*
Y282300D01*
G01X673280Y288330D02*
X678720D01*
G01X672950Y288000D02*
X673280Y288330D01*
G01X683625Y287330D02*
Y282250D01*
G01X682625Y288330D02*
X683625Y287330D01*
G01X678720Y288330D02*
X682625D01*
G01X682239Y269489D02*
X687500Y274750D01*
G01X682239Y268500D02*
Y269489D01*
G01X686912Y268500D02*
X682239D01*
G01X690443Y267927D02*
X691887D01*
G01X689870Y268500D02*
X690443Y267927D01*
G01X686912Y268500D02*
X689870D01*
G01X689181Y262854D02*
X686982D01*
G01X690754Y264427D02*
X689181Y262854D01*
G01X691887Y264427D02*
X690754D01*
G01X682489Y258650D02*
Y255684D01*
G01X682239Y258900D02*
X682489Y258650D01*
G01X682239Y262854D02*
Y258900D01*
G01X686982Y262854D02*
X682239D01*
G01X675127Y385633D02*
X676531D01*
G01X672627Y383133D02*
X675127Y385633D01*
G01X672131Y383133D02*
X672627D01*
G01X679567Y385633D02*
X680300Y384900D01*
G01X676531Y385633D02*
X679567D01*
G01X724200Y111600D02*
X720914Y114886D01*
G01X724200Y110700D02*
Y111600D01*
G01X741960Y108700D02*
X745700D01*
G01X741435Y108175D02*
X741960Y108700D01*
G01X736032Y108175D02*
X741435D01*
G01X734212Y109995D02*
X736032Y108175D01*
G01X722300Y99400D02*
X724600Y97100D01*
G01X722300Y103300D02*
Y99400D01*
G01X719010Y106590D02*
X722300Y103300D01*
G01X719010Y107281D02*
Y106590D01*
G01X734709Y105391D02*
X737100Y103000D01*
G01X734709Y106595D02*
Y105391D01*
G01X712200Y112500D02*
X713700D01*
G01X709702Y110002D02*
X712200Y112500D01*
G01X707649Y110002D02*
X709702D01*
G01X719000Y112700D02*
X716900Y114800D01*
G01X720744Y98590D02*
Y92427D01*
G01X712928Y106406D02*
X720744Y98590D01*
G01X712928Y107272D02*
Y106406D01*
G01X711539Y108661D02*
X712928Y107272D01*
G01X708892Y108661D02*
X711539D01*
G01X708181Y107950D02*
X708892Y108661D01*
G01X705414Y107950D02*
X708181D01*
G01X704849Y107385D02*
X705414Y107950D01*
G01X702798Y105102D02*
X701900Y106000D01*
G01X710466Y105102D02*
X702798D01*
G01X712725Y102843D02*
X710466Y105102D01*
G01X712725Y96514D02*
Y102843D01*
G01X718714Y90525D02*
X712725Y96514D01*
G01X725770Y90525D02*
X718714D01*
G01X733664Y90514D02*
X725770Y90525D01*
G01X741621Y82557D02*
X733664Y90514D01*
G01X747022Y82557D02*
X741621D01*
G01X750466Y79113D02*
X747022Y82557D01*
G01X757787Y79113D02*
X750466D01*
G01X759090Y77810D02*
X757787Y79113D01*
G01X759140Y77810D02*
X759090D01*
G01X761455Y75495D02*
X759140Y77810D01*
G01X700700Y110200D02*
Y115661D01*
G01X701263Y109637D02*
X700700Y110200D01*
G01X701263Y106637D02*
Y109637D01*
G01X701900Y106000D02*
X701263Y106637D01*
G01X714142Y100329D02*
X717087Y97384D01*
G01X714142Y103198D02*
Y100329D01*
G01X710517Y106823D02*
X714142Y103198D01*
G01X708300Y114500D02*
Y113300D01*
G01X724517Y103600D02*
X722673Y105444D01*
G01X725600Y103600D02*
X724517D01*
G01X757650Y94530D02*
X764100Y100980D01*
G01X757650Y91855D02*
Y94530D01*
G01X764458Y91855D02*
X757650D01*
G01X739275Y106525D02*
X742700Y103100D01*
G01X737800Y106525D02*
X739275D01*
G01X730200Y102941D02*
Y98200D01*
G01X726100Y107041D02*
X730200Y102941D01*
G01X726100Y107200D02*
Y107041D01*
G01X731000Y109900D02*
X734500Y113400D01*
G01X731000Y106315D02*
Y109900D01*
G01X717300Y109543D02*
X717197Y109646D01*
G01X717300Y105100D02*
Y109543D01*
G01X719500Y102900D02*
X717300Y105100D01*
G01X716200Y113093D02*
X714408Y114885D01*
G01X716200Y111100D02*
Y113093D01*
G01X715100Y110000D02*
X716200Y111100D01*
G01X715100Y107300D02*
Y110000D01*
G01X739100Y112500D02*
X736785Y110185D01*
G01X739900Y112500D02*
X739100D01*
G01X718140Y116535D02*
X717322D01*
G01X719789Y114886D02*
X718140Y116535D01*
G01X720914Y114886D02*
X719789D01*
G01X736368Y177952D02*
X733792Y175376D01*
G01X703073Y127483D02*
X704723Y129133D01*
G01X731022Y130235D02*
X733372D01*
G01X729921Y129134D02*
X731022Y130235D01*
G01X736467Y135433D02*
X738000Y133900D01*
G01X729921Y135433D02*
X736467D01*
G01X714117Y176322D02*
X711023Y173228D01*
G01X733296Y151899D02*
X736829D01*
G01X732579Y152616D02*
X733296Y151899D01*
G01X732161Y153034D02*
X732579Y152616D01*
G01X732161Y155240D02*
Y153034D01*
G01X729921Y157480D02*
X732161Y155240D01*
G01X736829Y151899D02*
Y155899D01*
G01X710294Y138406D02*
X713500Y135200D01*
G01X709497Y138406D02*
X710294D01*
G01X707861Y136770D02*
X709497Y138406D01*
G01X707861Y133930D02*
Y136770D01*
G01Y132294D02*
X711022Y129133D01*
G01X707861Y133930D02*
Y132294D01*
G01X733888Y160629D02*
X729921D01*
G01X734202Y160315D02*
X733888Y160629D01*
G01X731621Y149731D02*
X729921Y148031D01*
G01X742769Y149731D02*
X731621D01*
G01X747450Y145050D02*
X742769Y149731D01*
G01X749500Y145050D02*
X747450D01*
G01X753971D02*
X749500D01*
G01X732255Y120500D02*
X729921Y122834D01*
G01X733600Y120500D02*
X732255D01*
G01X747600Y114700D02*
X747700Y114800D01*
G01X743100Y114700D02*
X747600D01*
G01X750500Y169500D02*
X748000Y167000D01*
G01X753750Y169500D02*
X750500D01*
G01X744779Y163779D02*
X748000Y167000D01*
G01X729921Y163779D02*
X744779D01*
G01X737702Y126102D02*
X736800Y125200D01*
G01X737702Y128565D02*
Y126102D01*
G01X726235Y116535D02*
X727700Y118000D01*
G01X723622Y116535D02*
X726235D01*
G01X747950Y141000D02*
X750000D01*
G01X746622Y142328D02*
X747950Y141000D01*
G01X732167Y142328D02*
X746622D01*
G01X731571Y141732D02*
X732167Y142328D01*
G01X729921Y141732D02*
X731571D01*
G01X752617Y140433D02*
X757065D01*
G01X752050Y141000D02*
X752617Y140433D01*
G01X750000Y141000D02*
X752050D01*
G01X735488Y165280D02*
X736730Y166522D01*
G01X732385Y165280D02*
X735488D01*
G01X731920Y165745D02*
X732385Y165280D01*
G01X728737Y165745D02*
X731920D01*
G01X726771Y163779D02*
X728737Y165745D01*
G01X740885Y145885D02*
X741500Y146500D01*
G01X737352Y145885D02*
X740885D01*
G01X715908Y114800D02*
X714173Y116535D01*
G01X716900Y114800D02*
X715908D01*
G01X699999Y130708D02*
X701574Y129133D01*
G01X699999Y132427D02*
Y130708D01*
G01X700700Y115661D02*
X701575Y116536D01*
G01X707873Y129133D02*
X705223Y126483D01*
G01X754250Y160800D02*
X749533D01*
G01X746750Y160000D02*
Y157700D01*
G01X747550Y160800D02*
X746750Y160000D01*
G01X749533Y160800D02*
X747550D01*
G01X707874Y114926D02*
X708300Y114500D01*
G01X707874Y116535D02*
Y114926D01*
G01X730235Y132597D02*
X729921Y132283D01*
G01X735310Y132597D02*
X730235D01*
G01X737307Y130600D02*
X735310Y132597D01*
G01X742700Y130600D02*
X737307D01*
G01X753583Y136383D02*
X757065D01*
G01X752400Y135200D02*
X753583Y136383D01*
G01X750550Y135200D02*
X752400D01*
G01X741308Y137008D02*
X743400Y139100D01*
G01X739622Y137008D02*
X741308D01*
G01X732382Y144882D02*
X733500Y146000D01*
G01X729921Y144882D02*
X732382D01*
G01X732905Y123000D02*
X729921Y125984D01*
G01X748000Y123000D02*
X732905D01*
G01X752500Y127500D02*
X748000Y123000D01*
G01X757065Y132065D02*
X752500Y127500D01*
G01X757065Y132181D02*
Y132065D01*
G01X746615Y126815D02*
X747200Y127400D01*
G01X740952Y126815D02*
X746615D01*
G01X712673Y114885D02*
X711023Y116535D01*
G01X714408Y114885D02*
X712673D01*
G01X746383Y134617D02*
X746400Y134600D01*
G01X741754Y134617D02*
X746383D01*
G01X733882Y138582D02*
X734500Y139200D01*
G01X729921Y138582D02*
X733882D01*
G01X732006Y117600D02*
X726771Y122835D01*
G01X738200Y117600D02*
X732006D01*
G01X740074Y120527D02*
X739952Y120649D01*
G01X744222Y120527D02*
X740074D01*
G01X714172Y130172D02*
Y129133D01*
G01X715490Y131490D02*
X714172Y130172D01*
G01X717500Y133500D02*
Y135200D01*
G01X715490Y131490D02*
X717500Y133500D01*
G01X737315Y177952D02*
X736368D01*
G01X725855Y205727D02*
X726032Y205904D01*
G01X721734Y205727D02*
X725855D01*
G01X720357Y207104D02*
X721734Y205727D01*
G01X716040Y176322D02*
X714117D01*
G01X746189Y189552D02*
X746691D01*
G01X743752Y187115D02*
X746189Y189552D01*
G01X714195Y201596D02*
X714173Y201574D01*
G01X714195Y205336D02*
Y201596D01*
G01X717956Y209097D02*
X714195Y205336D01*
G01X717956Y212806D02*
Y209097D01*
G01X719700Y214550D02*
X717956Y212806D01*
G01X734611Y237027D02*
X760981D01*
G01X729407Y242231D02*
X734611Y237027D01*
G01X744586Y182715D02*
X745659Y183788D01*
G01X742502Y182715D02*
X744586D01*
G01X732639Y185827D02*
X734043Y187231D01*
G01X729920Y185827D02*
X732639D01*
G01X703290Y205505D02*
X706737D01*
G01X699968D02*
X703290D01*
G01X698541Y204078D02*
X699968Y205505D01*
G01X698541Y202639D02*
Y204078D01*
G01X742978Y204180D02*
X745485Y201673D01*
G01X742978Y206202D02*
Y204180D01*
G01X743867Y180115D02*
X745778Y178204D01*
G01X740352Y180115D02*
X743867D01*
G01X710687Y201911D02*
Y202564D01*
G01X714173Y198425D02*
X710687Y201911D01*
G01X718928Y205172D02*
X721500Y202600D01*
G01X718330Y205172D02*
X718928D01*
G01X733782Y235027D02*
X788433D01*
G01X728543Y240266D02*
X733782Y235027D01*
G01X735307Y181764D02*
X736078D01*
G01X733070Y179527D02*
X735307Y181764D01*
G01X710800Y207533D02*
X711310Y207023D01*
G01X710800Y214550D02*
Y207533D01*
G01X715300Y210674D02*
Y214400D01*
G01X715467Y210507D02*
X715300Y210674D01*
G01X728351Y257981D02*
X724380D01*
G01X732226Y261856D02*
X728351Y257981D01*
G01X759417Y261856D02*
X732226D01*
G01X761638Y259635D02*
X759417Y261856D01*
G01X719962Y261916D02*
X724380D01*
G01X710693Y252647D02*
X719962Y261916D01*
G01X704708Y252647D02*
X710693D01*
G01X735509Y241027D02*
X759558D01*
G01X735009Y240527D02*
X735509Y241027D01*
G01X735009Y239527D02*
Y240527D01*
G01X735509Y239027D02*
X735009Y239527D01*
G01X760981Y239027D02*
X735509D01*
G01X724380Y242231D02*
X729407D01*
G01X741169Y289480D02*
X739300Y287611D01*
G01X794651Y289480D02*
X741169D01*
G01X757555Y257678D02*
X755693Y259540D01*
G01X762004Y257678D02*
X757555D01*
G01X727492Y259951D02*
X724380D01*
G01X731397Y263856D02*
X727492Y259951D01*
G01X764034Y263856D02*
X731397D01*
G01X730117Y254046D02*
X724380D01*
G01X731611Y255540D02*
X730117Y254046D01*
G01X734638Y255540D02*
X731611D01*
G01X735138Y256040D02*
X734638Y255540D01*
G01X735138Y256771D02*
Y256040D01*
G01X735638Y257271D02*
X735138Y256771D01*
G01X736638Y257271D02*
X735638D01*
G01X737138Y256771D02*
X736638Y257271D01*
G01X737138Y256040D02*
Y256771D01*
G01X737638Y255540D02*
X737138Y256040D01*
G01X738638Y255540D02*
X737638D01*
G01X739138Y256040D02*
X738638Y255540D01*
G01X739138Y256771D02*
Y256040D01*
G01X739638Y257271D02*
X739138Y256771D01*
G01X740638Y257271D02*
X739638D01*
G01X741138Y256771D02*
X740638Y257271D01*
G01X741138Y256040D02*
Y256771D01*
G01X741638Y255540D02*
X741138Y256040D01*
G01X742638Y255540D02*
X741638D01*
G01X743138Y256040D02*
X742638Y255540D01*
G01X743138Y256771D02*
Y256040D01*
G01X743638Y257271D02*
X743138Y256771D01*
G01X744638Y257271D02*
X743638D01*
G01X745138Y256771D02*
X744638Y257271D01*
G01X745138Y256040D02*
Y256771D01*
G01X745638Y255540D02*
X745138Y256040D01*
G01X746638Y255540D02*
X745638D01*
G01X747138Y256040D02*
X746638Y255540D01*
G01X747138Y256771D02*
Y256040D01*
G01X747638Y257271D02*
X747138Y256771D01*
G01X748638Y257271D02*
X747638D01*
G01X749138Y256771D02*
X748638Y257271D01*
G01X749138Y256040D02*
Y256771D01*
G01X749638Y255540D02*
X749138Y256040D01*
G01X751693Y255540D02*
X749638D01*
G01X730833Y268987D02*
X769396D01*
G01X728059Y271761D02*
X730833Y268987D01*
G01X724380Y271761D02*
X728059D01*
G01X737640Y304380D02*
X729020Y295760D01*
G01X704708Y260647D02*
X700600Y256539D01*
G01X736812Y306381D02*
X728191Y297760D01*
G01X731851Y270987D02*
X771396D01*
G01X729107Y273731D02*
X731851Y270987D01*
G01X724380Y273731D02*
X729107D01*
G01X733230Y285541D02*
X735300Y287611D01*
G01X724380Y285541D02*
X733230D01*
G01X731822Y248141D02*
X724380D01*
G01X732689Y247274D02*
X731822Y248141D01*
G01X747558Y247274D02*
X732689D01*
G01X733348Y281601D02*
X735318Y283571D01*
G01X724380Y281601D02*
X733348D01*
G01X735358Y279611D02*
X739318Y283571D01*
G01X733696Y279611D02*
X735358D01*
G01X731751Y277666D02*
X733696Y279611D01*
G01X724380Y277666D02*
X731751D01*
G01X730543Y252076D02*
X724380D01*
G01X731195Y252728D02*
X730543Y252076D01*
G01X742464Y252728D02*
X731195D01*
G01X743507Y251685D02*
X742464Y252728D01*
G01X731155Y279636D02*
X724380D01*
G01X716096Y276558D02*
Y272396D01*
G01X717825Y267826D02*
X724380D01*
G01X716096Y269555D02*
X717825Y267826D01*
G01X716096Y272396D02*
Y269555D01*
G01X730401Y244201D02*
X724380D01*
G01X731437Y243165D02*
X730401Y244201D01*
G01X763175Y243165D02*
X731437D01*
G01X759320Y253417D02*
X761484Y255581D01*
G01X754843Y253417D02*
X759320D01*
G01X754343Y252917D02*
X754843Y253417D01*
G01X754343Y250916D02*
Y252917D01*
G01X753843Y250416D02*
X754343Y250916D01*
G01X752843Y250416D02*
X753843D01*
G01X752343Y250916D02*
X752843Y250416D01*
G01X752343Y252917D02*
Y250916D01*
G01X751843Y253417D02*
X752343Y252917D01*
G01X750843Y253417D02*
X751843D01*
G01X750343Y252917D02*
X750843Y253417D01*
G01X750343Y250770D02*
Y252917D01*
G01X749843Y250270D02*
X750343Y250770D01*
G01X748843Y250270D02*
X749843D01*
G01X748343Y250770D02*
X748843Y250270D01*
G01X748343Y252917D02*
Y250770D01*
G01X747843Y253417D02*
X748343Y252917D01*
G01X746843Y253417D02*
X747843D01*
G01X746343Y252917D02*
X746843Y253417D01*
G01X746343Y249812D02*
Y252917D01*
G01X745843Y249312D02*
X746343Y249812D01*
G01X733529Y249312D02*
X745843D01*
G01X732735Y250106D02*
X733529Y249312D01*
G01X724380Y250106D02*
X732735D01*
G01X758182Y249567D02*
X759470D01*
G01X757682Y249067D02*
X758182Y249567D01*
G01X757682Y245893D02*
Y249067D01*
G01X757182Y245393D02*
X757682Y245893D01*
G01X756182Y245393D02*
X757182D01*
G01X755682Y245893D02*
X756182Y245393D01*
G01X755682Y247582D02*
Y245893D01*
G01X755182Y248082D02*
X755682Y247582D01*
G01X754182Y248082D02*
X755182D01*
G01X753682Y247582D02*
X754182Y248082D01*
G01X753682Y245789D02*
Y247582D01*
G01X753182Y245289D02*
X753682Y245789D01*
G01X752182Y245289D02*
X753182D01*
G01X751682Y245789D02*
X752182Y245289D01*
G01X751682Y247623D02*
Y245789D01*
G01X751182Y248123D02*
X751682Y247623D01*
G01X750182Y248123D02*
X751182D01*
G01X749682Y247623D02*
X750182Y248123D01*
G01X749682Y245697D02*
Y247623D01*
G01X749182Y245197D02*
X749682Y245697D01*
G01X732213Y245197D02*
X749182D01*
G01X731239Y246171D02*
X732213Y245197D01*
G01X724380Y246171D02*
X731239D01*
G01X724380Y265856D02*
X765100D01*
G01X724380Y240266D02*
X728543D01*
G01X729210Y256011D02*
X724380D01*
G01X732739Y259540D02*
X729210Y256011D01*
G01X751693Y259540D02*
X732739D01*
G01X707377Y256647D02*
X704708D01*
G01X714616Y263886D02*
X707377Y256647D01*
G01X724380Y263886D02*
X714616D01*
G01X724380Y283571D02*
X731318D01*
G01X731200Y287511D02*
X724380D01*
G01X731300Y287611D02*
X731200Y287511D01*
G01X733438Y274496D02*
X734638Y275696D01*
G01X730864Y274496D02*
X733438D01*
G01X729664Y275696D02*
X730864Y274496D01*
G01X724380Y275696D02*
X729664D01*
G01X797988Y304380D02*
X737640D01*
G01X799919Y306381D02*
X736812D01*
G01X739680Y429140D02*
Y423900D01*
G01X785050Y79020D02*
Y79670D01*
G01X784280Y78250D02*
X785050Y79020D01*
G01X779875Y78250D02*
X784280D01*
G01X785050Y83950D02*
X785350Y84250D01*
G01X785050Y79670D02*
Y83950D01*
G01X787250Y84250D02*
X785350D01*
G01X789500Y82000D02*
X787250Y84250D01*
G01X789500Y80000D02*
Y82000D01*
G01X791000Y78500D02*
X789500Y80000D01*
G01X791750Y78500D02*
X791000D01*
G01X769475Y88805D02*
X766694Y86024D01*
G01X772398Y88805D02*
X769475D01*
G01X775453Y85750D02*
X772398Y88805D01*
G01X776000Y85750D02*
X775453D01*
G01X762590Y81870D02*
X762620Y81900D01*
G01X762590Y77810D02*
Y81870D01*
G01X762620Y81950D02*
Y81900D01*
G01X766694Y86024D02*
X762620Y81950D01*
G01X787250Y95250D02*
X790000Y92500D01*
G01X785350Y95250D02*
X787250D01*
G01X779250D02*
X776500Y92500D01*
G01X781000Y95250D02*
X779250D01*
G01X766125Y75495D02*
X761455D01*
G01X767359Y76729D02*
X766125Y75495D01*
G01X767359Y82076D02*
Y76729D01*
G01X776500Y98500D02*
X771371D01*
G01X767920D02*
X771371D01*
G01X765150Y95730D02*
X767920Y98500D01*
G01X764100Y100980D02*
Y115200D01*
G01X765530Y90783D02*
X764458Y91855D01*
G01X765530Y89010D02*
Y90783D01*
G01X762620Y86100D02*
X765530Y89010D01*
G01X799250Y79845D02*
Y82375D01*
G01X788780Y69375D02*
X799250Y79845D01*
G01X773115Y69375D02*
X788780D01*
G01X763560Y59820D02*
X773115Y69375D01*
G01X803375Y95625D02*
Y93250D01*
G01X801800Y97200D02*
X803375Y95625D01*
G01X794200Y97200D02*
X801800D01*
G01X792800Y95800D02*
X794200Y97200D01*
G01X792800Y90500D02*
Y95800D01*
G01X791700Y89400D02*
X792800Y90500D01*
G01X790100Y89400D02*
X791700D01*
G01X788287Y87587D02*
X790100Y89400D01*
G01X788287Y86087D02*
Y87587D01*
G01X792250Y100750D02*
X790000Y98500D01*
G01X799500Y100750D02*
X792250D01*
G01X790000Y149597D02*
X785756Y145353D01*
G01X790000Y152000D02*
Y149597D01*
G01X782500Y142097D02*
Y140850D01*
G01X785756Y145353D02*
X782500Y142097D01*
G01Y140850D02*
X786500D01*
G01X793378Y146779D02*
Y145309D01*
G01X795000Y148401D02*
X793378Y146779D01*
G01X795000Y152000D02*
Y148401D01*
G01X794500Y141903D02*
Y140850D01*
G01X793378Y143025D02*
X794500Y141903D01*
G01X793378Y145309D02*
Y143025D01*
G01X794500Y140850D02*
X790500D01*
G01X795000Y172000D02*
Y178100D01*
G01X790000Y172000D02*
Y178300D01*
G01X785000Y172000D02*
Y175750D01*
G01X800000Y145240D02*
Y152000D01*
G01Y144004D02*
Y145240D01*
G01X798500Y142504D02*
X800000Y144004D01*
G01X798500Y140850D02*
Y142504D01*
G01X802696Y140850D02*
X798500D01*
G01X765900Y131800D02*
X768900Y134800D01*
G01X765900Y119700D02*
Y131800D01*
G01Y117000D02*
Y119700D01*
G01X764100Y115200D02*
X765900Y117000D01*
G01X760981Y237027D02*
X761481Y237527D01*
G01X795000Y178100D02*
X795450Y178550D01*
G01X796110Y179210D02*
X795450Y178550D01*
G01X796110Y182850D02*
Y179210D01*
G01X790000Y178300D02*
X790050Y178350D01*
G01X791200Y179500D02*
X790050Y178350D01*
G01X791200Y182850D02*
Y179500D01*
G01X787700Y180300D02*
X786400Y179000D01*
G01X787700Y182850D02*
Y180300D01*
G01X792000Y232750D02*
X796500D01*
G01X800500D02*
X796500D01*
G01X804000Y236250D02*
Y243500D01*
G01X800500Y232750D02*
X804000Y236250D01*
G01X779791Y179241D02*
X779200Y178650D01*
G01X779791Y182831D02*
Y179241D01*
G01X782850Y177900D02*
Y178350D01*
G01X785000Y175750D02*
X782850Y177900D01*
G01Y182390D02*
Y178350D01*
G01X783291Y182831D02*
X782850Y182390D01*
G01X764175Y237350D02*
X763675Y237850D01*
G01X765175Y237350D02*
X764175D01*
G01X765675Y237850D02*
X765175Y237350D01*
G01X768175Y237224D02*
X767675Y237724D01*
G01X780337Y237224D02*
X768175D01*
G01X780837Y237724D02*
X780337Y237224D01*
G01X788433Y235027D02*
X790714Y237308D01*
G01X767227Y254046D02*
X765638Y255635D01*
G01X800080Y254046D02*
X767227D01*
G01X761481Y238527D02*
X760981Y239027D01*
G01X761481Y237527D02*
Y238527D01*
G01X790742Y277666D02*
X800080D01*
G01X784837Y271761D02*
X790742Y277666D01*
G01X800080Y275696D02*
X793837D01*
G01X796620Y287511D02*
X794651Y289480D01*
G01X800080Y287511D02*
X796620D01*
G01X763485Y256197D02*
X762004Y257678D01*
G01X763485Y254959D02*
Y256197D01*
G01X770303Y248141D02*
X763485Y254959D01*
G01X800080Y248141D02*
X770303D01*
G01X768144Y259746D02*
X764034Y263856D01*
G01X774637Y259746D02*
X768144D01*
G01X782687Y265976D02*
X780837Y267826D01*
G01X785976Y265976D02*
X782687D01*
G01X789791Y269791D02*
X785976Y265976D01*
G01X800080Y269791D02*
X789791D01*
G01X784837Y259951D02*
X800080D01*
G01X769396Y268987D02*
X770637Y267746D01*
G01X792215Y265856D02*
X800080D01*
G01X791715Y265356D02*
X792215Y265856D01*
G01X791715Y261565D02*
Y265356D01*
G01X791215Y261065D02*
X791715Y261565D01*
G01X790215Y261065D02*
X791215D01*
G01X789715Y261565D02*
X790215Y261065D01*
G01X789715Y264856D02*
Y261565D01*
G01X789215Y265356D02*
X789715Y264856D01*
G01X788232Y265356D02*
X789215D01*
G01X786767Y263891D02*
X788232Y265356D01*
G01X784837Y263891D02*
X786767D01*
G01X790742Y273731D02*
X800080D01*
G01X784837Y267826D02*
X790742Y273731D01*
G01X763401Y247274D02*
X759558D01*
G01X763901Y246774D02*
X763401Y247274D01*
G01X763901Y245261D02*
Y246774D01*
G01X764401Y244761D02*
X763901Y245261D01*
G01X765401Y244761D02*
X764401D01*
G01X765901Y245261D02*
X765401Y244761D01*
G01X765901Y246865D02*
Y245261D01*
G01X766401Y247365D02*
X765901Y246865D01*
G01X767401Y247365D02*
X766401D01*
G01X767901Y246865D02*
X767401Y247365D01*
G01X767901Y244369D02*
Y246865D01*
G01X768401Y243869D02*
X767901Y244369D01*
G01X769401Y243869D02*
X768401D01*
G01X769901Y244369D02*
X769401Y243869D01*
G01X769901Y245351D02*
Y244369D01*
G01X770401Y245851D02*
X769901Y245351D01*
G01X771401Y245851D02*
X770401D01*
G01X771901Y245351D02*
X771401Y245851D01*
G01X771901Y240432D02*
Y245351D01*
G01X772401Y239932D02*
X771901Y240432D01*
G01X773401Y239932D02*
X772401D01*
G01X773901Y240432D02*
X773401Y239932D01*
G01X773901Y245351D02*
Y240432D01*
G01X774401Y245851D02*
X773901Y245351D01*
G01X775401Y245851D02*
X774401D01*
G01X775901Y245351D02*
X775401Y245851D01*
G01X775901Y240391D02*
Y245351D01*
G01X776401Y239891D02*
X775901Y240391D01*
G01X777401Y239891D02*
X776401D01*
G01X777901Y240391D02*
X777401Y239891D01*
G01X777901Y245351D02*
Y240391D01*
G01X778401Y245851D02*
X777901Y245351D01*
G01X779401Y245851D02*
X778401D01*
G01X779901Y245351D02*
X779401Y245851D01*
G01X779901Y243385D02*
Y245351D01*
G01X780401Y242885D02*
X779901Y243385D01*
G01X781401Y242885D02*
X780401D01*
G01X781901Y243385D02*
X781401Y242885D01*
G01X781901Y245351D02*
Y243385D01*
G01X782401Y245851D02*
X781901Y245351D01*
G01X783401Y245851D02*
X782401D01*
G01X783901Y245351D02*
X783401Y245851D01*
G01X783901Y239597D02*
Y245351D01*
G01X784401Y239097D02*
X783901Y239597D01*
G01X785401Y239097D02*
X784401D01*
G01X785901Y239597D02*
X785401Y239097D01*
G01X785901Y245351D02*
Y239597D01*
G01X786401Y245851D02*
X785901Y245351D01*
G01X787401Y245851D02*
X786401D01*
G01X787901Y245351D02*
X787401Y245851D01*
G01X787901Y239659D02*
Y245351D01*
G01X788401Y239159D02*
X787901Y239659D01*
G01X789401Y239159D02*
X788401D01*
G01X789901Y239659D02*
X789401Y239159D01*
G01X789901Y245351D02*
Y239659D01*
G01X790401Y245851D02*
X789901Y245351D01*
G01X791401Y245851D02*
X790401D01*
G01X791901Y245351D02*
X791401Y245851D01*
G01X791901Y240141D02*
Y245351D01*
G01X792401Y239641D02*
X791901Y240141D01*
G01X793401Y239641D02*
X792401D01*
G01X793901Y240141D02*
X793401Y239641D01*
G01X793901Y241731D02*
Y240141D01*
G01X794401Y242231D02*
X793901Y241731D01*
G01X800080Y242231D02*
X794401D01*
G01X800080Y252076D02*
X793852D01*
G01X792593Y257981D02*
X800080D01*
G01X791752Y257140D02*
X792593Y257981D01*
G01X775798Y257140D02*
X791752D01*
G01X774657Y255999D02*
X775798Y257140D01*
G01X791962Y250106D02*
X800080D01*
G01X790021Y252046D02*
X791962Y250106D01*
G01X788734Y252046D02*
X790021D01*
G01X788234Y251546D02*
X788734Y252046D01*
G01X788234Y250957D02*
Y251546D01*
G01X787734Y250457D02*
X788234Y250957D01*
G01X786734Y250457D02*
X787734D01*
G01X786234Y250957D02*
X786734Y250457D01*
G01X786234Y251546D02*
Y250957D01*
G01X785734Y252046D02*
X786234Y251546D01*
G01X784734Y252046D02*
X785734D01*
G01X784234Y251546D02*
X784734Y252046D01*
G01X784234Y250957D02*
Y251546D01*
G01X783734Y250457D02*
X784234Y250957D01*
G01X782734Y250457D02*
X783734D01*
G01X782234Y250957D02*
X782734Y250457D01*
G01X782234Y251546D02*
Y250957D01*
G01X781734Y252046D02*
X782234Y251546D01*
G01X780734Y252046D02*
X781734D01*
G01X780234Y251546D02*
X780734Y252046D01*
G01X780234Y250957D02*
Y251546D01*
G01X779734Y250457D02*
X780234Y250957D01*
G01X778734Y250457D02*
X779734D01*
G01X778234Y250957D02*
X778734Y250457D01*
G01X778234Y251376D02*
Y250957D01*
G01X777734Y251876D02*
X778234Y251376D01*
G01X774637Y251876D02*
X777734D01*
G01X771396Y270987D02*
X774637Y267746D01*
G01X803299Y244201D02*
X800080D01*
G01X804000Y243500D02*
X803299Y244201D01*
G01X795617Y261916D02*
X800080D01*
G01X793837Y263696D02*
X795617Y261916D01*
G01X800080Y267826D02*
X793837D01*
G01X800080Y279636D02*
X793837D01*
G01X763675Y242665D02*
X763175Y243165D01*
G01X763675Y237850D02*
Y242665D01*
G01X765675Y241498D02*
Y237850D01*
G01X766175Y241998D02*
X765675Y241498D01*
G01X767175Y241998D02*
X766175D01*
G01X767675Y241498D02*
X767175Y241998D01*
G01X767675Y237724D02*
Y241498D01*
G01X780837Y240885D02*
Y237724D01*
G01X795992Y285541D02*
X800080D01*
G01X793837Y287696D02*
X795992Y285541D01*
G01X759470Y249567D02*
X761484Y251581D01*
G01X767210Y263746D02*
X774637D01*
G01X765100Y265856D02*
X767210Y263746D01*
G01X800080Y256011D02*
X793852D01*
G01X790677Y281601D02*
X780837Y271761D01*
G01X800080Y281601D02*
X790677D01*
G01X800080Y271761D02*
X793837D01*
G01X801853Y300515D02*
X797988Y304380D01*
G01X801728Y304572D02*
X799919Y306381D01*
G54D12*
G01X6250Y-135162D02*
Y-152662D01*
G01X1228Y-135162D02*
X11272D01*
G01X20038Y-152662D02*
Y-135162D01*
G01Y-143620D02*
X21130Y-142162D01*
X22222Y-141287D01*
X23968Y-140996D01*
X25278Y-141287D01*
X26807Y-142454D01*
X27462Y-144204D01*
Y-152662D01*
G01X41250Y-140996D02*
Y-152662D01*
G01Y-136329D02*
X40813Y-136037D01*
Y-135454D01*
X41250Y-135162D01*
X41687Y-135454D01*
Y-136037D01*
X41250Y-136329D01*
G01X55475Y-150621D02*
X56567Y-151787D01*
X58095Y-152662D01*
X59405D01*
X60715Y-152079D01*
X61588Y-151204D01*
X62025Y-150038D01*
X61807Y-148287D01*
X60933Y-147412D01*
X57003Y-145662D01*
X56130Y-143620D01*
X56567Y-142162D01*
X57440Y-141287D01*
X58750Y-140996D01*
X60060Y-141287D01*
X61370Y-142162D01*
G01X90693Y-157037D02*
X92222Y-158204D01*
X93968Y-158495D01*
X95496Y-158204D01*
X96807Y-156746D01*
X97680Y-154704D01*
Y-140996D01*
G01Y-143329D02*
X96807Y-142162D01*
X95496Y-141287D01*
X93968Y-140996D01*
X92222Y-141579D01*
X91130Y-142745D01*
X90256Y-144787D01*
X89820Y-146829D01*
X90038Y-148579D01*
X90912Y-150621D01*
X92222Y-152079D01*
X93968Y-152662D01*
X95278Y-152370D01*
X96807Y-151204D01*
X97680Y-150038D01*
G01X107975Y-144787D02*
X114962D01*
X114307Y-142745D01*
X113215Y-141579D01*
X111687Y-140996D01*
X110158Y-141287D01*
X108848Y-142162D01*
X107975Y-144204D01*
X107538Y-145954D01*
Y-147704D01*
X107975Y-149454D01*
X109067Y-151204D01*
X110377Y-152370D01*
X111905Y-152662D01*
X113433Y-152079D01*
X114962Y-150329D01*
G01X125693Y-152662D02*
Y-140996D01*
G01Y-143329D02*
X126785Y-142162D01*
X127877Y-141287D01*
X129405Y-140996D01*
X130496Y-141287D01*
X131807Y-142162D01*
G01X142320Y-152662D02*
Y-135162D01*
G01Y-143912D02*
X143412Y-142162D01*
X144722Y-141287D01*
X146032Y-140996D01*
X147996Y-141579D01*
X149307Y-142745D01*
X150180Y-144787D01*
Y-147120D01*
X149743Y-149454D01*
X148870Y-151204D01*
X147342Y-152370D01*
X146032Y-152662D01*
X144722Y-152370D01*
X143412Y-151496D01*
X142320Y-150038D01*
G01X160475Y-144787D02*
X167462D01*
X166807Y-142745D01*
X165715Y-141579D01*
X164187Y-140996D01*
X162658Y-141287D01*
X161348Y-142162D01*
X160475Y-144204D01*
X160038Y-145954D01*
Y-147704D01*
X160475Y-149454D01*
X161567Y-151204D01*
X162877Y-152370D01*
X164405Y-152662D01*
X165933Y-152079D01*
X167462Y-150329D01*
G01X178193Y-152662D02*
Y-140996D01*
G01Y-143329D02*
X179285Y-142162D01*
X180377Y-141287D01*
X181905Y-140996D01*
X182996Y-141287D01*
X184307Y-142162D01*
G01X216250Y-140996D02*
Y-152662D01*
G01Y-136329D02*
X215813Y-136037D01*
Y-135454D01*
X216250Y-135162D01*
X216687Y-135454D01*
Y-136037D01*
X216250Y-136329D01*
G01X230475Y-150621D02*
X231567Y-151787D01*
X233095Y-152662D01*
X234405D01*
X235715Y-152079D01*
X236588Y-151204D01*
X237025Y-150038D01*
X236807Y-148287D01*
X235933Y-147412D01*
X232003Y-145662D01*
X231130Y-143620D01*
X231567Y-142162D01*
X232440Y-141287D01*
X233750Y-140996D01*
X235060Y-141287D01*
X236370Y-142162D01*
G01X265256Y-157037D02*
X266785Y-158204D01*
X268095Y-158495D01*
X269842Y-157912D01*
X271152Y-156454D01*
X271807Y-153828D01*
Y-140996D01*
G01Y-136329D02*
X271370Y-136037D01*
Y-135454D01*
X271807Y-135162D01*
X272243Y-135454D01*
Y-136037D01*
X271807Y-136329D01*
G01X282538Y-140996D02*
Y-149162D01*
X283412Y-151204D01*
X284722Y-152370D01*
X286250Y-152662D01*
X287778Y-152370D01*
X289088Y-151204D01*
X289962Y-149162D01*
G01Y-152662D02*
Y-140996D01*
G01X300475Y-150621D02*
X301567Y-151787D01*
X303095Y-152662D01*
X304405D01*
X305715Y-152079D01*
X306588Y-151204D01*
X307025Y-150038D01*
X306807Y-148287D01*
X305933Y-147412D01*
X302003Y-145662D01*
X301130Y-143620D01*
X301567Y-142162D01*
X302440Y-141287D01*
X303750Y-140996D01*
X305060Y-141287D01*
X306370Y-142162D01*
G01X321250Y-135162D02*
Y-152662D01*
G01X318193Y-140996D02*
X324307D01*
G01X354940Y-152662D02*
Y-137787D01*
X355377Y-136329D01*
X356250Y-135454D01*
X357560Y-135162D01*
X358870Y-135745D01*
X359525Y-137204D01*
G01X356905Y-142162D02*
X352538D01*
G01X373750Y-152662D02*
X372440Y-152370D01*
X371130Y-151204D01*
X370256Y-149162D01*
X369820Y-146829D01*
X370256Y-144495D01*
X371130Y-142454D01*
X372440Y-141287D01*
X373750Y-140996D01*
X375060Y-141287D01*
X376370Y-142454D01*
X377243Y-144495D01*
X377462Y-146829D01*
X377243Y-149162D01*
X376370Y-151204D01*
X375060Y-152370D01*
X373750Y-152662D01*
G01X388193D02*
Y-140996D01*
G01Y-143329D02*
X389285Y-142162D01*
X390377Y-141287D01*
X391905Y-140996D01*
X392996Y-141287D01*
X394307Y-142162D01*
G01X421665Y-157912D02*
X422975Y-158495D01*
X424722Y-157912D01*
X425813Y-156746D01*
X426687Y-155287D01*
X427996Y-150621D01*
X430835Y-140996D01*
G01X423848D02*
X427996Y-150621D01*
G01X443750Y-152662D02*
X442440Y-152370D01*
X441130Y-151204D01*
X440256Y-149162D01*
X439820Y-146829D01*
X440256Y-144495D01*
X441130Y-142454D01*
X442440Y-141287D01*
X443750Y-140996D01*
X445060Y-141287D01*
X446370Y-142454D01*
X447243Y-144495D01*
X447462Y-146829D01*
X447243Y-149162D01*
X446370Y-151204D01*
X445060Y-152370D01*
X443750Y-152662D01*
G01X457538Y-140996D02*
Y-149162D01*
X458412Y-151204D01*
X459722Y-152370D01*
X461250Y-152662D01*
X462778Y-152370D01*
X464088Y-151204D01*
X464962Y-149162D01*
G01Y-152662D02*
Y-140996D01*
G01X475693Y-152662D02*
Y-140996D01*
G01Y-143329D02*
X476785Y-142162D01*
X477877Y-141287D01*
X479405Y-140996D01*
X480496Y-141287D01*
X481807Y-142162D01*
G01X510693Y-152662D02*
Y-140996D01*
G01Y-143329D02*
X511785Y-142162D01*
X512877Y-141287D01*
X514405Y-140996D01*
X515496Y-141287D01*
X516807Y-142162D01*
G01X527975Y-144787D02*
X534962D01*
X534307Y-142745D01*
X533215Y-141579D01*
X531687Y-140996D01*
X530158Y-141287D01*
X528848Y-142162D01*
X527975Y-144204D01*
X527538Y-145954D01*
Y-147704D01*
X527975Y-149454D01*
X529067Y-151204D01*
X530377Y-152370D01*
X531905Y-152662D01*
X533433Y-152079D01*
X534962Y-150329D01*
G01X547440Y-152662D02*
Y-137787D01*
X547877Y-136329D01*
X548750Y-135454D01*
X550060Y-135162D01*
X551370Y-135745D01*
X552025Y-137204D01*
G01X549405Y-142162D02*
X545038D01*
G01X562975Y-144787D02*
X569962D01*
X569307Y-142745D01*
X568215Y-141579D01*
X566687Y-140996D01*
X565158Y-141287D01*
X563848Y-142162D01*
X562975Y-144204D01*
X562538Y-145954D01*
Y-147704D01*
X562975Y-149454D01*
X564067Y-151204D01*
X565377Y-152370D01*
X566905Y-152662D01*
X568433Y-152079D01*
X569962Y-150329D01*
G01X580693Y-152662D02*
Y-140996D01*
G01Y-143329D02*
X581785Y-142162D01*
X582877Y-141287D01*
X584405Y-140996D01*
X585496Y-141287D01*
X586807Y-142162D01*
G01X597975Y-144787D02*
X604962D01*
X604307Y-142745D01*
X603215Y-141579D01*
X601687Y-140996D01*
X600158Y-141287D01*
X598848Y-142162D01*
X597975Y-144204D01*
X597538Y-145954D01*
Y-147704D01*
X597975Y-149454D01*
X599067Y-151204D01*
X600377Y-152370D01*
X601905Y-152662D01*
X603433Y-152079D01*
X604962Y-150329D01*
G01X615038Y-152662D02*
Y-140996D01*
G01Y-143912D02*
X615912Y-142454D01*
X617222Y-141287D01*
X618968Y-140996D01*
X620496Y-141287D01*
X621807Y-142454D01*
X622462Y-144495D01*
Y-152662D01*
G01X639743Y-142454D02*
X638215Y-141287D01*
X636905Y-140996D01*
X635158Y-141579D01*
X633848Y-142745D01*
X632975Y-144787D01*
X632756Y-146829D01*
X632975Y-148871D01*
X633848Y-150621D01*
X635158Y-152079D01*
X636905Y-152662D01*
X638433Y-152079D01*
X639743Y-150912D01*
G01X650475Y-144787D02*
X657462D01*
X656807Y-142745D01*
X655715Y-141579D01*
X654187Y-140996D01*
X652658Y-141287D01*
X651348Y-142162D01*
X650475Y-144204D01*
X650038Y-145954D01*
Y-147704D01*
X650475Y-149454D01*
X651567Y-151204D01*
X652877Y-152370D01*
X654405Y-152662D01*
X655933Y-152079D01*
X657462Y-150329D01*
G01X688750Y-135162D02*
Y-152662D01*
G01X685693Y-140996D02*
X691807D01*
G01X706250Y-152662D02*
X704940Y-152370D01*
X703630Y-151204D01*
X702756Y-149162D01*
X702320Y-146829D01*
X702756Y-144495D01*
X703630Y-142454D01*
X704940Y-141287D01*
X706250Y-140996D01*
X707560Y-141287D01*
X708870Y-142454D01*
X709743Y-144495D01*
X709962Y-146829D01*
X709743Y-149162D01*
X708870Y-151204D01*
X707560Y-152370D01*
X706250Y-152662D01*
G01X739940D02*
Y-137787D01*
X740377Y-136329D01*
X741250Y-135454D01*
X742560Y-135162D01*
X743870Y-135745D01*
X744525Y-137204D01*
G01X741905Y-142162D02*
X737538D01*
G01X758750Y-140996D02*
Y-152662D01*
G01Y-136329D02*
X758313Y-136037D01*
Y-135454D01*
X758750Y-135162D01*
X759187Y-135454D01*
Y-136037D01*
X758750Y-136329D01*
G01X772538Y-152662D02*
Y-140996D01*
G01Y-143912D02*
X773412Y-142454D01*
X774722Y-141287D01*
X776468Y-140996D01*
X777996Y-141287D01*
X779307Y-142454D01*
X779962Y-144495D01*
Y-152662D01*
G01X797680Y-135162D02*
Y-152662D01*
G01Y-150038D02*
X796807Y-151496D01*
X795496Y-152370D01*
X793968Y-152662D01*
X792222Y-152079D01*
X790912Y-150621D01*
X790038Y-148871D01*
X789820Y-146829D01*
X790038Y-144787D01*
X790912Y-143037D01*
X792222Y-141579D01*
X793968Y-140996D01*
X795496Y-141287D01*
X796588Y-141871D01*
X797680Y-143037D01*
G01X828750Y-135162D02*
Y-152662D01*
G01X825693Y-140996D02*
X831807D01*
G01X842538Y-152662D02*
Y-135162D01*
G01Y-143620D02*
X843630Y-142162D01*
X844722Y-141287D01*
X846468Y-140996D01*
X847778Y-141287D01*
X849307Y-142454D01*
X849962Y-144204D01*
Y-152662D01*
G01X860475Y-144787D02*
X867462D01*
X866807Y-142745D01*
X865715Y-141579D01*
X864187Y-140996D01*
X862658Y-141287D01*
X861348Y-142162D01*
X860475Y-144204D01*
X860038Y-145954D01*
Y-147704D01*
X860475Y-149454D01*
X861567Y-151204D01*
X862877Y-152370D01*
X864405Y-152662D01*
X865933Y-152079D01*
X867462Y-150329D01*
G01X894165D02*
X895912Y-151787D01*
X897877Y-152662D01*
X899623D01*
X901370Y-151787D01*
X902680Y-150329D01*
X903335Y-148287D01*
X902898Y-146246D01*
X901807Y-144495D01*
X899842Y-143329D01*
X897222Y-142745D01*
X895693Y-141579D01*
X895038Y-139537D01*
X895475Y-137495D01*
X896567Y-136037D01*
X898095Y-135162D01*
X899623D01*
X901152Y-135745D01*
X902462Y-137204D01*
G01X920617Y-152662D02*
X911883D01*
Y-135162D01*
X920617D01*
G01X917123Y-143620D02*
X911883D01*
G01X951250Y-140996D02*
Y-152662D01*
G01Y-136329D02*
X950813Y-136037D01*
Y-135454D01*
X951250Y-135162D01*
X951687Y-135454D01*
Y-136037D01*
X951250Y-136329D01*
G01X962200Y-152662D02*
Y-140996D01*
G01Y-144204D02*
X962855Y-142745D01*
X963947Y-141579D01*
X965475Y-140996D01*
X967003Y-141579D01*
X968095Y-142745D01*
X968750Y-144204D01*
Y-152662D01*
G01Y-144204D02*
X969405Y-142745D01*
X970496Y-141579D01*
X972025Y-140996D01*
X973553Y-141579D01*
X974645Y-142745D01*
X975300Y-144495D01*
Y-152662D01*
G01X982320Y-158495D02*
Y-140996D01*
G01Y-143620D02*
X983412Y-142162D01*
X984503Y-141287D01*
X986250Y-140996D01*
X987778Y-141287D01*
X989307Y-142745D01*
X989962Y-144787D01*
X990180Y-146829D01*
X989962Y-148871D01*
X989307Y-150912D01*
X987996Y-152079D01*
X986250Y-152662D01*
X984722Y-152370D01*
X983193Y-151496D01*
X982320Y-150329D01*
G01X1000475Y-144787D02*
X1007462D01*
X1006807Y-142745D01*
X1005715Y-141579D01*
X1004187Y-140996D01*
X1002658Y-141287D01*
X1001348Y-142162D01*
X1000475Y-144204D01*
X1000038Y-145954D01*
Y-147704D01*
X1000475Y-149454D01*
X1001567Y-151204D01*
X1002877Y-152370D01*
X1004405Y-152662D01*
X1005933Y-152079D01*
X1007462Y-150329D01*
G01X1025180Y-135162D02*
Y-152662D01*
G01Y-150038D02*
X1024307Y-151496D01*
X1022996Y-152370D01*
X1021468Y-152662D01*
X1019722Y-152079D01*
X1018412Y-150621D01*
X1017538Y-148871D01*
X1017320Y-146829D01*
X1017538Y-144787D01*
X1018412Y-143037D01*
X1019722Y-141579D01*
X1021468Y-140996D01*
X1022996Y-141287D01*
X1024088Y-141871D01*
X1025180Y-143037D01*
G01X1042680Y-152662D02*
Y-140996D01*
G01Y-143037D02*
X1041807Y-141871D01*
X1040496Y-141287D01*
X1038968Y-140996D01*
X1037440Y-141579D01*
X1036130Y-142745D01*
X1035256Y-144495D01*
X1034820Y-146829D01*
X1035256Y-149162D01*
X1036130Y-150912D01*
X1037440Y-152079D01*
X1038968Y-152662D01*
X1040496Y-152370D01*
X1041807Y-151496D01*
X1042680Y-150329D01*
G01X1052538Y-152662D02*
Y-140996D01*
G01Y-143912D02*
X1053412Y-142454D01*
X1054722Y-141287D01*
X1056468Y-140996D01*
X1057996Y-141287D01*
X1059307Y-142454D01*
X1059962Y-144495D01*
Y-152662D01*
G01X1077243Y-142454D02*
X1075715Y-141287D01*
X1074405Y-140996D01*
X1072658Y-141579D01*
X1071348Y-142745D01*
X1070475Y-144787D01*
X1070256Y-146829D01*
X1070475Y-148871D01*
X1071348Y-150621D01*
X1072658Y-152079D01*
X1074405Y-152662D01*
X1075933Y-152079D01*
X1077243Y-150912D01*
G01X1087975Y-144787D02*
X1094962D01*
X1094307Y-142745D01*
X1093215Y-141579D01*
X1091687Y-140996D01*
X1090158Y-141287D01*
X1088848Y-142162D01*
X1087975Y-144204D01*
X1087538Y-145954D01*
Y-147704D01*
X1087975Y-149454D01*
X1089067Y-151204D01*
X1090377Y-152370D01*
X1091905Y-152662D01*
X1093433Y-152079D01*
X1094962Y-150329D01*
G01X1126250Y-135162D02*
Y-152662D01*
G01X1123193Y-140996D02*
X1129307D01*
G01X1140693Y-152662D02*
Y-140996D01*
G01Y-143329D02*
X1141785Y-142162D01*
X1142877Y-141287D01*
X1144405Y-140996D01*
X1145496Y-141287D01*
X1146807Y-142162D01*
G01X1165180Y-152662D02*
Y-140996D01*
G01Y-143037D02*
X1164307Y-141871D01*
X1162996Y-141287D01*
X1161468Y-140996D01*
X1159940Y-141579D01*
X1158630Y-142745D01*
X1157756Y-144495D01*
X1157320Y-146829D01*
X1157756Y-149162D01*
X1158630Y-150912D01*
X1159940Y-152079D01*
X1161468Y-152662D01*
X1162996Y-152370D01*
X1164307Y-151496D01*
X1165180Y-150329D01*
G01X1182243Y-142454D02*
X1180715Y-141287D01*
X1179405Y-140996D01*
X1177658Y-141579D01*
X1176348Y-142745D01*
X1175475Y-144787D01*
X1175256Y-146829D01*
X1175475Y-148871D01*
X1176348Y-150621D01*
X1177658Y-152079D01*
X1179405Y-152662D01*
X1180933Y-152079D01*
X1182243Y-150912D01*
G01X1192975Y-144787D02*
X1199962D01*
X1199307Y-142745D01*
X1198215Y-141579D01*
X1196687Y-140996D01*
X1195158Y-141287D01*
X1193848Y-142162D01*
X1192975Y-144204D01*
X1192538Y-145954D01*
Y-147704D01*
X1192975Y-149454D01*
X1194067Y-151204D01*
X1195377Y-152370D01*
X1196905Y-152662D01*
X1198433Y-152079D01*
X1199962Y-150329D01*
G01X1210475Y-150621D02*
X1211567Y-151787D01*
X1213095Y-152662D01*
X1214405D01*
X1215715Y-152079D01*
X1216588Y-151204D01*
X1217025Y-150038D01*
X1216807Y-148287D01*
X1215933Y-147412D01*
X1212003Y-145662D01*
X1211130Y-143620D01*
X1211567Y-142162D01*
X1212440Y-141287D01*
X1213750Y-140996D01*
X1215060Y-141287D01*
X1216370Y-142162D01*
G01X1248750Y-140996D02*
Y-152662D01*
G01Y-136329D02*
X1248313Y-136037D01*
Y-135454D01*
X1248750Y-135162D01*
X1249187Y-135454D01*
Y-136037D01*
X1248750Y-136329D01*
G01X1262538Y-152662D02*
Y-140996D01*
G01Y-143912D02*
X1263412Y-142454D01*
X1264722Y-141287D01*
X1266468Y-140996D01*
X1267996Y-141287D01*
X1269307Y-142454D01*
X1269962Y-144495D01*
Y-152662D01*
G01X1301250D02*
Y-135162D01*
G01X1322680Y-152662D02*
Y-140996D01*
G01Y-143037D02*
X1321807Y-141871D01*
X1320496Y-141287D01*
X1318968Y-140996D01*
X1317440Y-141579D01*
X1316130Y-142745D01*
X1315256Y-144495D01*
X1314820Y-146829D01*
X1315256Y-149162D01*
X1316130Y-150912D01*
X1317440Y-152079D01*
X1318968Y-152662D01*
X1320496Y-152370D01*
X1321807Y-151496D01*
X1322680Y-150329D01*
G01X1331665Y-157912D02*
X1332975Y-158495D01*
X1334722Y-157912D01*
X1335813Y-156746D01*
X1336687Y-155287D01*
X1337996Y-150621D01*
X1340835Y-140996D01*
G01X1333848D02*
X1337996Y-150621D01*
G01X1350475Y-144787D02*
X1357462D01*
X1356807Y-142745D01*
X1355715Y-141579D01*
X1354187Y-140996D01*
X1352658Y-141287D01*
X1351348Y-142162D01*
X1350475Y-144204D01*
X1350038Y-145954D01*
Y-147704D01*
X1350475Y-149454D01*
X1351567Y-151204D01*
X1352877Y-152370D01*
X1354405Y-152662D01*
X1355933Y-152079D01*
X1357462Y-150329D01*
G01X1368193Y-152662D02*
Y-140996D01*
G01Y-143329D02*
X1369285Y-142162D01*
X1370377Y-141287D01*
X1371905Y-140996D01*
X1372996Y-141287D01*
X1374307Y-142162D01*
G01X1401883Y-135162D02*
Y-152662D01*
X1410617D01*
G01X1423750D02*
X1425278Y-152370D01*
X1427025Y-151496D01*
X1428117Y-150038D01*
X1428553Y-147995D01*
X1428117Y-145954D01*
X1426807Y-144204D01*
X1424842Y-143329D01*
X1422658D01*
X1421348Y-142745D01*
X1420256Y-141287D01*
X1419820Y-139246D01*
X1420475Y-137204D01*
X1422003Y-135745D01*
X1423750Y-135162D01*
X1425496Y-135745D01*
X1427025Y-137204D01*
X1427680Y-139246D01*
X1427243Y-141287D01*
X1426152Y-142745D01*
X1424842Y-143329D01*
X1422658D01*
X1420693Y-144204D01*
X1419383Y-145954D01*
X1418947Y-147995D01*
X1419383Y-150038D01*
X1420475Y-151496D01*
X1422222Y-152370D01*
X1423750Y-152662D01*
G01X1441250Y-153245D02*
X1440813Y-152954D01*
Y-152370D01*
X1441250Y-152079D01*
X1441687Y-152370D01*
Y-152954D01*
X1441250Y-153245D01*
G01X879036Y548599D02*
X880783Y547141D01*
X882748Y546266D01*
X884494D01*
X886241Y547141D01*
X887551Y548599D01*
X888206Y550641D01*
X887769Y552682D01*
X886678Y554433D01*
X884713Y555599D01*
X882093Y556183D01*
X880564Y557349D01*
X879909Y559391D01*
X880346Y561433D01*
X881438Y562891D01*
X882966Y563766D01*
X884494D01*
X886023Y563183D01*
X887333Y561724D01*
G01X905488Y546266D02*
X896754D01*
Y563766D01*
X905488D01*
G01X901994Y555308D02*
X896754D01*
G01X933501Y563766D02*
X938741D01*
G01X936121D02*
Y546266D01*
G01X933501D02*
X938741D01*
G01X947944D02*
Y563766D01*
X953621Y549183D01*
X959298Y563766D01*
Y546266D01*
G01X966754D02*
Y563766D01*
X971994D01*
X973741Y562891D01*
X975051Y560849D01*
X975488Y558516D01*
X975051Y556183D01*
X973959Y554433D01*
X971994Y553557D01*
X966754D01*
G01X992988Y546266D02*
X984254D01*
Y563766D01*
X992988D01*
G01X989494Y555308D02*
X984254D01*
G01X1001318Y546266D02*
Y563766D01*
X1005684D01*
X1007431Y562891D01*
X1008741Y561724D01*
X1009833Y559975D01*
X1010706Y557932D01*
X1010924Y555016D01*
X1010706Y552099D01*
X1009833Y550057D01*
X1008741Y548307D01*
X1007431Y547141D01*
X1005684Y546266D01*
X1001318D01*
G01X1018162D02*
X1023621Y563766D01*
X1029080Y546266D01*
G01X1027114Y552391D02*
X1020127D01*
G01X1036099Y546266D02*
Y563766D01*
X1046143Y546266D01*
Y563766D01*
G01X1063424Y562307D02*
X1062114Y563183D01*
X1060586Y563766D01*
X1058839D01*
X1056874Y562891D01*
X1055346Y561433D01*
X1054254Y559682D01*
X1053381Y556766D01*
X1053162Y554141D01*
X1053599Y551516D01*
X1054254Y549766D01*
X1055564Y548016D01*
X1057093Y546849D01*
X1058621Y546266D01*
X1060149D01*
X1061678Y546849D01*
X1062988Y547724D01*
X1064080Y548890D01*
G01X1080488Y546266D02*
X1071754D01*
Y563766D01*
X1080488D01*
G01X1076994Y555308D02*
X1071754D01*
G01X1111121Y563766D02*
Y546266D01*
G01X1106099Y563766D02*
X1116143D01*
G01X1123162Y546266D02*
X1128621Y563766D01*
X1134080Y546266D01*
G01X1132114Y552391D02*
X1125127D01*
G01X1147867Y555599D02*
X1148741Y556474D01*
X1149396Y557932D01*
X1149833Y559975D01*
X1149396Y561724D01*
X1148523Y562891D01*
X1146994Y563766D01*
X1141099D01*
Y546266D01*
X1148304D01*
X1149833Y547432D01*
X1150706Y549183D01*
X1151143Y551224D01*
X1150706Y553266D01*
X1149396Y555016D01*
X1147867Y555599D01*
X1141099D01*
G01X1159254Y563766D02*
Y546266D01*
X1167988D01*
G01X1185488D02*
X1176754D01*
Y563766D01*
X1185488D01*
G01X1181994Y555308D02*
X1176754D01*
G01X1198621Y545683D02*
X1198184Y545974D01*
Y546558D01*
X1198621Y546849D01*
X1199058Y546558D01*
Y545974D01*
X1198621Y545683D01*
G01Y553557D02*
X1198184Y553849D01*
Y554433D01*
X1198621Y554724D01*
X1199058Y554433D01*
Y553849D01*
X1198621Y553557D01*
G01X1229254Y563766D02*
Y546266D01*
X1237988D01*
G01X1251121D02*
X1252649Y546558D01*
X1254396Y547432D01*
X1255488Y548890D01*
X1255924Y550933D01*
X1255488Y552974D01*
X1254178Y554724D01*
X1252213Y555599D01*
X1250029D01*
X1248719Y556183D01*
X1247627Y557641D01*
X1247191Y559682D01*
X1247846Y561724D01*
X1249374Y563183D01*
X1251121Y563766D01*
X1252867Y563183D01*
X1254396Y561724D01*
X1255051Y559682D01*
X1254614Y557641D01*
X1253523Y556183D01*
X1252213Y555599D01*
X1250029D01*
X1248064Y554724D01*
X1246754Y552974D01*
X1246318Y550933D01*
X1246754Y548890D01*
X1247846Y547432D01*
X1249593Y546558D01*
X1251121Y546266D01*
G01X933518Y479590D02*
X934827Y478132D01*
X936356Y477258D01*
X938321Y476966D01*
X940286Y477549D01*
X941814Y478716D01*
X942906Y480757D01*
X943124Y483091D01*
X942688Y485424D01*
X941596Y486883D01*
X940067Y488049D01*
X938539Y488341D01*
X937011Y488049D01*
X935046Y486883D01*
X935701Y494466D01*
X941596D01*
G01X955821D02*
X954074Y493883D01*
X952764Y492424D01*
X951891Y490675D01*
X951236Y488341D01*
X951018Y485716D01*
X951236Y483091D01*
X951891Y480757D01*
X952764Y479007D01*
X954074Y477549D01*
X955821Y476966D01*
X957567Y477549D01*
X958878Y479007D01*
X959751Y480757D01*
X960406Y483091D01*
X960624Y485716D01*
X960406Y488341D01*
X959751Y490675D01*
X958878Y492424D01*
X957567Y493883D01*
X955821Y494466D01*
G01X973321Y476383D02*
X972884Y476674D01*
Y477258D01*
X973321Y477549D01*
X973758Y477258D01*
Y476674D01*
X973321Y476383D01*
G01X990821Y494466D02*
X989074Y493883D01*
X987764Y492424D01*
X986891Y490675D01*
X986236Y488341D01*
X986018Y485716D01*
X986236Y483091D01*
X986891Y480757D01*
X987764Y479007D01*
X989074Y477549D01*
X990821Y476966D01*
X992567Y477549D01*
X993878Y479007D01*
X994751Y480757D01*
X995406Y483091D01*
X995624Y485716D01*
X995406Y488341D01*
X994751Y490675D01*
X993878Y492424D01*
X992567Y493883D01*
X990821Y494466D01*
G01X900701Y529116D02*
X905941D01*
G01X903321D02*
Y511616D01*
G01X900701D02*
X905941D01*
G01X915144D02*
Y529116D01*
X920821Y514533D01*
X926498Y529116D01*
Y511616D01*
G01X933954D02*
Y529116D01*
X939194D01*
X940941Y528241D01*
X942251Y526199D01*
X942688Y523866D01*
X942251Y521533D01*
X941159Y519783D01*
X939194Y518907D01*
X933954D01*
G01X954729Y505783D02*
X952546Y508699D01*
X951454Y511616D01*
Y523282D01*
X952546Y526199D01*
X954729Y529116D01*
G01X973321Y511616D02*
X971574Y511908D01*
X970046Y513074D01*
X968736Y514824D01*
X967862Y516866D01*
X967426Y519199D01*
Y521533D01*
X967862Y523866D01*
X968736Y525908D01*
X970046Y527657D01*
X971574Y528824D01*
X973321Y529116D01*
X975067Y528824D01*
X976596Y527657D01*
X977906Y525908D01*
X978780Y523866D01*
X979216Y521533D01*
Y519199D01*
X978780Y516866D01*
X977906Y514824D01*
X976596Y513074D01*
X975067Y511908D01*
X973321Y511616D01*
G01X987109D02*
Y529116D01*
G01Y520658D02*
X988201Y522116D01*
X989293Y522991D01*
X991039Y523282D01*
X992349Y522991D01*
X993878Y521824D01*
X994533Y520074D01*
Y511616D01*
G01X1001771D02*
Y523282D01*
G01Y520074D02*
X1002426Y521533D01*
X1003518Y522699D01*
X1005046Y523282D01*
X1006574Y522699D01*
X1007666Y521533D01*
X1008321Y520074D01*
Y511616D01*
G01Y520074D02*
X1008976Y521533D01*
X1010067Y522699D01*
X1011596Y523282D01*
X1013124Y522699D01*
X1014216Y521533D01*
X1014871Y519783D01*
Y511616D01*
G01X1026913Y505783D02*
X1029096Y508699D01*
X1030188Y511616D01*
Y523282D01*
X1029096Y526199D01*
X1026913Y529116D01*
G01X1071771D02*
X1074827Y511616D01*
X1078321Y529116D01*
X1081814Y511616D01*
X1084871Y529116D01*
G01X1093201D02*
X1098441D01*
G01X1095821D02*
Y511616D01*
G01X1093201D02*
X1098441D01*
G01X1108518D02*
Y529116D01*
X1112884D01*
X1114631Y528241D01*
X1115941Y527074D01*
X1117033Y525325D01*
X1117906Y523282D01*
X1118124Y520366D01*
X1117906Y517449D01*
X1117033Y515407D01*
X1115941Y513657D01*
X1114631Y512491D01*
X1112884Y511616D01*
X1108518D01*
G01X1130821Y529116D02*
Y511616D01*
G01X1125799Y529116D02*
X1135843D01*
G01X1143736Y511616D02*
Y529116D01*
G01X1152906D02*
Y511616D01*
G01Y520366D02*
X1143736D01*
G01X1164729Y505783D02*
X1162546Y508699D01*
X1161454Y511616D01*
Y523282D01*
X1162546Y526199D01*
X1164729Y529116D01*
G01X1176771Y511616D02*
Y523282D01*
G01Y520074D02*
X1177426Y521533D01*
X1178518Y522699D01*
X1180046Y523282D01*
X1181574Y522699D01*
X1182666Y521533D01*
X1183321Y520074D01*
Y511616D01*
G01Y520074D02*
X1183976Y521533D01*
X1185067Y522699D01*
X1186596Y523282D01*
X1188124Y522699D01*
X1189216Y521533D01*
X1189871Y519783D01*
Y511616D01*
G01X1200821Y523282D02*
Y511616D01*
G01Y527949D02*
X1200384Y528241D01*
Y528824D01*
X1200821Y529116D01*
X1201258Y528824D01*
Y528241D01*
X1200821Y527949D01*
G01X1218321Y511616D02*
Y529116D01*
G01X1232546Y513657D02*
X1233638Y512491D01*
X1235166Y511616D01*
X1236476D01*
X1237786Y512199D01*
X1238659Y513074D01*
X1239096Y514240D01*
X1238878Y515991D01*
X1238004Y516866D01*
X1234074Y518616D01*
X1233201Y520658D01*
X1233638Y522116D01*
X1234511Y522991D01*
X1235821Y523282D01*
X1237131Y522991D01*
X1238441Y522116D01*
G01X1254413Y505783D02*
X1256596Y508699D01*
X1257688Y511616D01*
Y523282D01*
X1256596Y526199D01*
X1254413Y529116D01*
G01X1143518Y479590D02*
X1144827Y478132D01*
X1146356Y477258D01*
X1148321Y476966D01*
X1150286Y477549D01*
X1151814Y478716D01*
X1152906Y480757D01*
X1153124Y483091D01*
X1152688Y485424D01*
X1151596Y486883D01*
X1150067Y488049D01*
X1148539Y488341D01*
X1147011Y488049D01*
X1145046Y486883D01*
X1145701Y494466D01*
X1151596D01*
G01X1165821Y476383D02*
X1165384Y476674D01*
Y477258D01*
X1165821Y477549D01*
X1166258Y477258D01*
Y476674D01*
X1165821Y476383D01*
G01X1183321Y494466D02*
X1181574Y493883D01*
X1180264Y492424D01*
X1179391Y490675D01*
X1178736Y488341D01*
X1178518Y485716D01*
X1178736Y483091D01*
X1179391Y480757D01*
X1180264Y479007D01*
X1181574Y477549D01*
X1183321Y476966D01*
X1185067Y477549D01*
X1186378Y479007D01*
X1187251Y480757D01*
X1187906Y483091D01*
X1188124Y485716D01*
X1187906Y488341D01*
X1187251Y490675D01*
X1186378Y492424D01*
X1185067Y493883D01*
X1183321Y494466D01*
G01X1318736Y479299D02*
X1320483Y477841D01*
X1322448Y476966D01*
X1324194D01*
X1325941Y477841D01*
X1327251Y479299D01*
X1327906Y481341D01*
X1327469Y483382D01*
X1326378Y485133D01*
X1324413Y486299D01*
X1321793Y486883D01*
X1320264Y488049D01*
X1319609Y490091D01*
X1320046Y492133D01*
X1321138Y493591D01*
X1322666Y494466D01*
X1324194D01*
X1325723Y493883D01*
X1327033Y492424D01*
G01X1345188Y476966D02*
X1336454D01*
Y494466D01*
X1345188D01*
G01X1341694Y486008D02*
X1336454D01*
G01X1305821Y529116D02*
Y511616D01*
G01X1300799Y529116D02*
X1310843D01*
G01X1323321Y511616D02*
Y519491D01*
X1318954Y529116D01*
G01X1327688D02*
X1323321Y519491D01*
G01X1336454Y511616D02*
Y529116D01*
X1341694D01*
X1343441Y528241D01*
X1344751Y526199D01*
X1345188Y523866D01*
X1344751Y521533D01*
X1343659Y519783D01*
X1341694Y518907D01*
X1336454D01*
G01X1362688Y511616D02*
X1353954D01*
Y529116D01*
X1362688D01*
G01X1359194Y520658D02*
X1353954D01*
G01X1406454Y511616D02*
Y529116D01*
X1411913D01*
X1413659Y528241D01*
X1414751Y527074D01*
X1415188Y524741D01*
X1414751Y522407D01*
X1413441Y520949D01*
X1411913Y520074D01*
X1406454D01*
G01X1411913D02*
X1415188Y511616D01*
G01X1425046Y519491D02*
X1432033D01*
X1431378Y521533D01*
X1430286Y522699D01*
X1428758Y523282D01*
X1427229Y522991D01*
X1425919Y522116D01*
X1425046Y520074D01*
X1424609Y518324D01*
Y516574D01*
X1425046Y514824D01*
X1426138Y513074D01*
X1427448Y511908D01*
X1428976Y511616D01*
X1430504Y512199D01*
X1432033Y513949D01*
G01X1444511Y511616D02*
Y526491D01*
X1444948Y527949D01*
X1445821Y528824D01*
X1447131Y529116D01*
X1448441Y528533D01*
X1449096Y527074D01*
G01X1446476Y522116D02*
X1442109D01*
G01X1463321Y511033D02*
X1462884Y511324D01*
Y511908D01*
X1463321Y512199D01*
X1463758Y511908D01*
Y511324D01*
X1463321Y511033D01*
G01X1493954Y511616D02*
Y529116D01*
X1499194D01*
X1500941Y528241D01*
X1502251Y526199D01*
X1502688Y523866D01*
X1502251Y521533D01*
X1501159Y519783D01*
X1499194Y518907D01*
X1493954D01*
G01X1515821Y511616D02*
Y529116D01*
G01X1537251Y511616D02*
Y523282D01*
G01Y521241D02*
X1536378Y522407D01*
X1535067Y522991D01*
X1533539Y523282D01*
X1532011Y522699D01*
X1530701Y521533D01*
X1529827Y519783D01*
X1529391Y517449D01*
X1529827Y515116D01*
X1530701Y513366D01*
X1532011Y512199D01*
X1533539Y511616D01*
X1535067Y511908D01*
X1536378Y512782D01*
X1537251Y513949D01*
G01X1547109Y511616D02*
Y523282D01*
G01Y520366D02*
X1547983Y521824D01*
X1549293Y522991D01*
X1551039Y523282D01*
X1552567Y522991D01*
X1553878Y521824D01*
X1554533Y519783D01*
Y511616D01*
G01X1565046Y519491D02*
X1572033D01*
X1571378Y521533D01*
X1570286Y522699D01*
X1568758Y523282D01*
X1567229Y522991D01*
X1565919Y522116D01*
X1565046Y520074D01*
X1564609Y518324D01*
Y516574D01*
X1565046Y514824D01*
X1566138Y513074D01*
X1567448Y511908D01*
X1568976Y511616D01*
X1570504Y512199D01*
X1572033Y513949D01*
G01X1476454Y494466D02*
Y476966D01*
X1485188D01*
G01X1497884D02*
X1498321Y480757D01*
X1498976Y483966D01*
X1499849Y486883D01*
X1500941Y490091D01*
X1502688Y494466D01*
X1493954D01*
G01X1686121Y488632D02*
Y476966D01*
G01Y493299D02*
X1685684Y493591D01*
Y494174D01*
X1686121Y494466D01*
X1686558Y494174D01*
Y493591D01*
X1686121Y493299D01*
G01X1700346Y479007D02*
X1701438Y477841D01*
X1702966Y476966D01*
X1704276D01*
X1705586Y477549D01*
X1706459Y478424D01*
X1706896Y479590D01*
X1706678Y481341D01*
X1705804Y482216D01*
X1701874Y483966D01*
X1701001Y486008D01*
X1701438Y487466D01*
X1702311Y488341D01*
X1703621Y488632D01*
X1704931Y488341D01*
X1706241Y487466D01*
G01X1733599Y476966D02*
Y494466D01*
X1743643Y476966D01*
Y494466D01*
G01X1756121Y476966D02*
X1754374Y477258D01*
X1752846Y478424D01*
X1751536Y480174D01*
X1750662Y482216D01*
X1750226Y484549D01*
Y486883D01*
X1750662Y489216D01*
X1751536Y491258D01*
X1752846Y493007D01*
X1754374Y494174D01*
X1756121Y494466D01*
X1757867Y494174D01*
X1759396Y493007D01*
X1760706Y491258D01*
X1761580Y489216D01*
X1762016Y486883D01*
Y484549D01*
X1761580Y482216D01*
X1760706Y480174D01*
X1759396Y478424D01*
X1757867Y477258D01*
X1756121Y476966D01*
G01X1773621Y494466D02*
Y476966D01*
G01X1768599Y494466D02*
X1778643D01*
G01X1804909Y488632D02*
Y480466D01*
X1805783Y478424D01*
X1807093Y477258D01*
X1808621Y476966D01*
X1810149Y477258D01*
X1811459Y478424D01*
X1812333Y480466D01*
G01Y476966D02*
Y488632D01*
G01X1822846Y479007D02*
X1823938Y477841D01*
X1825466Y476966D01*
X1826776D01*
X1828086Y477549D01*
X1828959Y478424D01*
X1829396Y479590D01*
X1829178Y481341D01*
X1828304Y482216D01*
X1824374Y483966D01*
X1823501Y486008D01*
X1823938Y487466D01*
X1824811Y488341D01*
X1826121Y488632D01*
X1827431Y488341D01*
X1828741Y487466D01*
G01X1840346Y484841D02*
X1847333D01*
X1846678Y486883D01*
X1845586Y488049D01*
X1844058Y488632D01*
X1842529Y488341D01*
X1841219Y487466D01*
X1840346Y485424D01*
X1839909Y483674D01*
Y481924D01*
X1840346Y480174D01*
X1841438Y478424D01*
X1842748Y477258D01*
X1844276Y476966D01*
X1845804Y477549D01*
X1847333Y479299D01*
G01X1865051Y494466D02*
Y476966D01*
G01Y479590D02*
X1864178Y478132D01*
X1862867Y477258D01*
X1861339Y476966D01*
X1859593Y477549D01*
X1858283Y479007D01*
X1857409Y480757D01*
X1857191Y482799D01*
X1857409Y484841D01*
X1858283Y486591D01*
X1859593Y488049D01*
X1861339Y488632D01*
X1862867Y488341D01*
X1863959Y487757D01*
X1865051Y486591D01*
G01X1611318Y511033D02*
X1620924Y523866D01*
G01X1616121Y526199D02*
Y508699D01*
G01X1620924Y511033D02*
X1611318Y523866D01*
G01X1609571Y517449D02*
X1622671D01*
G01X1648283D02*
X1653959D01*
G01X1681318Y511616D02*
Y529116D01*
X1685684D01*
X1687431Y528241D01*
X1688741Y527074D01*
X1689833Y525325D01*
X1690706Y523282D01*
X1690924Y520366D01*
X1690706Y517449D01*
X1689833Y515407D01*
X1688741Y513657D01*
X1687431Y512491D01*
X1685684Y511616D01*
X1681318D01*
G01X1700346Y519491D02*
X1707333D01*
X1706678Y521533D01*
X1705586Y522699D01*
X1704058Y523282D01*
X1702529Y522991D01*
X1701219Y522116D01*
X1700346Y520074D01*
X1699909Y518324D01*
Y516574D01*
X1700346Y514824D01*
X1701438Y513074D01*
X1702748Y511908D01*
X1704276Y511616D01*
X1705804Y512199D01*
X1707333Y513949D01*
G01X1717409Y511616D02*
Y523282D01*
G01Y520366D02*
X1718283Y521824D01*
X1719593Y522991D01*
X1721339Y523282D01*
X1722867Y522991D01*
X1724178Y521824D01*
X1724833Y519783D01*
Y511616D01*
G01X1738621D02*
X1737311Y511908D01*
X1736001Y513074D01*
X1735127Y515116D01*
X1734691Y517449D01*
X1735127Y519783D01*
X1736001Y521824D01*
X1737311Y522991D01*
X1738621Y523282D01*
X1739931Y522991D01*
X1741241Y521824D01*
X1742114Y519783D01*
X1742333Y517449D01*
X1742114Y515116D01*
X1741241Y513074D01*
X1739931Y511908D01*
X1738621Y511616D01*
G01X1756121Y529116D02*
Y511616D01*
G01X1753064Y523282D02*
X1759178D01*
G01X1770346Y519491D02*
X1777333D01*
X1776678Y521533D01*
X1775586Y522699D01*
X1774058Y523282D01*
X1772529Y522991D01*
X1771219Y522116D01*
X1770346Y520074D01*
X1769909Y518324D01*
Y516574D01*
X1770346Y514824D01*
X1771438Y513074D01*
X1772748Y511908D01*
X1774276Y511616D01*
X1775804Y512199D01*
X1777333Y513949D01*
G01X1787846Y513657D02*
X1788938Y512491D01*
X1790466Y511616D01*
X1791776D01*
X1793086Y512199D01*
X1793959Y513074D01*
X1794396Y514240D01*
X1794178Y515991D01*
X1793304Y516866D01*
X1789374Y518616D01*
X1788501Y520658D01*
X1788938Y522116D01*
X1789811Y522991D01*
X1791121Y523282D01*
X1792431Y522991D01*
X1793741Y522116D01*
G01X1826121Y529116D02*
Y511616D01*
G01X1823064Y523282D02*
X1829178D01*
G01X1839909Y511616D02*
Y529116D01*
G01Y520658D02*
X1841001Y522116D01*
X1842093Y522991D01*
X1843839Y523282D01*
X1845149Y522991D01*
X1846678Y521824D01*
X1847333Y520074D01*
Y511616D01*
G01X1865051D02*
Y523282D01*
G01Y521241D02*
X1864178Y522407D01*
X1862867Y522991D01*
X1861339Y523282D01*
X1859811Y522699D01*
X1858501Y521533D01*
X1857627Y519783D01*
X1857191Y517449D01*
X1857627Y515116D01*
X1858501Y513366D01*
X1859811Y512199D01*
X1861339Y511616D01*
X1862867Y511908D01*
X1864178Y512782D01*
X1865051Y513949D01*
G01X1878621Y529116D02*
Y511616D01*
G01X1875564Y523282D02*
X1881678D01*
G01X1913621Y529116D02*
Y511616D01*
G01X1910564Y523282D02*
X1916678D01*
G01X1927409Y511616D02*
Y529116D01*
G01Y520658D02*
X1928501Y522116D01*
X1929593Y522991D01*
X1931339Y523282D01*
X1932649Y522991D01*
X1934178Y521824D01*
X1934833Y520074D01*
Y511616D01*
G01X1948621Y523282D02*
Y511616D01*
G01Y527949D02*
X1948184Y528241D01*
Y528824D01*
X1948621Y529116D01*
X1949058Y528824D01*
Y528241D01*
X1948621Y527949D01*
G01X1962846Y513657D02*
X1963938Y512491D01*
X1965466Y511616D01*
X1966776D01*
X1968086Y512199D01*
X1968959Y513074D01*
X1969396Y514240D01*
X1969178Y515991D01*
X1968304Y516866D01*
X1964374Y518616D01*
X1963501Y520658D01*
X1963938Y522116D01*
X1964811Y522991D01*
X1966121Y523282D01*
X1967431Y522991D01*
X1968741Y522116D01*
G01X1998501Y529116D02*
X2003741D01*
G01X2001121D02*
Y511616D01*
G01X1998501D02*
X2003741D01*
G01X2012071D02*
Y523282D01*
G01Y520074D02*
X2012726Y521533D01*
X2013818Y522699D01*
X2015346Y523282D01*
X2016874Y522699D01*
X2017966Y521533D01*
X2018621Y520074D01*
Y511616D01*
G01Y520074D02*
X2019276Y521533D01*
X2020367Y522699D01*
X2021896Y523282D01*
X2023424Y522699D01*
X2024516Y521533D01*
X2025171Y519783D01*
Y511616D01*
G01X2032191Y505783D02*
Y523282D01*
G01Y520658D02*
X2033283Y522116D01*
X2034374Y522991D01*
X2036121Y523282D01*
X2037649Y522991D01*
X2039178Y521533D01*
X2039833Y519491D01*
X2040051Y517449D01*
X2039833Y515407D01*
X2039178Y513366D01*
X2037867Y512199D01*
X2036121Y511616D01*
X2034593Y511908D01*
X2033064Y512782D01*
X2032191Y513949D01*
G01X2050346Y519491D02*
X2057333D01*
X2056678Y521533D01*
X2055586Y522699D01*
X2054058Y523282D01*
X2052529Y522991D01*
X2051219Y522116D01*
X2050346Y520074D01*
X2049909Y518324D01*
Y516574D01*
X2050346Y514824D01*
X2051438Y513074D01*
X2052748Y511908D01*
X2054276Y511616D01*
X2055804Y512199D01*
X2057333Y513949D01*
G01X2075051Y529116D02*
Y511616D01*
G01Y514240D02*
X2074178Y512782D01*
X2072867Y511908D01*
X2071339Y511616D01*
X2069593Y512199D01*
X2068283Y513657D01*
X2067409Y515407D01*
X2067191Y517449D01*
X2067409Y519491D01*
X2068283Y521241D01*
X2069593Y522699D01*
X2071339Y523282D01*
X2072867Y522991D01*
X2073959Y522407D01*
X2075051Y521241D01*
G01X2092551Y511616D02*
Y523282D01*
G01Y521241D02*
X2091678Y522407D01*
X2090367Y522991D01*
X2088839Y523282D01*
X2087311Y522699D01*
X2086001Y521533D01*
X2085127Y519783D01*
X2084691Y517449D01*
X2085127Y515116D01*
X2086001Y513366D01*
X2087311Y512199D01*
X2088839Y511616D01*
X2090367Y511908D01*
X2091678Y512782D01*
X2092551Y513949D01*
G01X2102409Y511616D02*
Y523282D01*
G01Y520366D02*
X2103283Y521824D01*
X2104593Y522991D01*
X2106339Y523282D01*
X2107867Y522991D01*
X2109178Y521824D01*
X2109833Y519783D01*
Y511616D01*
G01X2127114Y521824D02*
X2125586Y522991D01*
X2124276Y523282D01*
X2122529Y522699D01*
X2121219Y521533D01*
X2120346Y519491D01*
X2120127Y517449D01*
X2120346Y515407D01*
X2121219Y513657D01*
X2122529Y512199D01*
X2124276Y511616D01*
X2125804Y512199D01*
X2127114Y513366D01*
G01X2137846Y519491D02*
X2144833D01*
X2144178Y521533D01*
X2143086Y522699D01*
X2141558Y523282D01*
X2140029Y522991D01*
X2138719Y522116D01*
X2137846Y520074D01*
X2137409Y518324D01*
Y516574D01*
X2137846Y514824D01*
X2138938Y513074D01*
X2140248Y511908D01*
X2141776Y511616D01*
X2143304Y512199D01*
X2144833Y513949D01*
G01X20103Y-86244D02*
G03I-4291J0D01*
G01X0Y-87362D02*
G03X15000Y-102362I15000J0D01*
G01X0Y-11811D02*
Y-87362D01*
G01X3937Y-7874D02*
G03X0Y-11811I0J-3937D01*
G01X15748Y-7874D02*
X3937D01*
G01X0Y7874D02*
G03X7874Y0I7874J0D01*
G01X818897D02*
X7874D01*
G01X0Y7874D02*
Y562992D01*
G01X7874Y570866D02*
G03X0Y562992I0J-7874D01*
G01X7874Y570866D02*
X326781D01*
G01X312004Y-102362D02*
X15000D01*
G01X46456Y0D02*
G03Y-7874I0J-3937D01*
G01X15748D02*
G03Y0I0J3937D01*
G01X287400Y-7874D02*
X46456D01*
G01X40452Y499724D02*
G03I-3051J0D01*
G01X41535Y535157D02*
G03I-4134J0D01*
G01X44685Y517441D02*
G03I-7284J0D01*
G01X121082Y39055D02*
G03I-5019J0D01*
G01X120807Y14567D02*
G03I-4744J0D01*
G01X319878Y-102362D02*
G03X312004I-3937J0D01*
G01X811771D02*
X319878D01*
G01X326770Y0D02*
G03Y-7874I0J-3937D01*
G01X287400D02*
G03Y0I0J3937D01*
G01X302165Y531496D02*
G03I-6890J0D01*
G01X597707Y-7874D02*
X326770D01*
G01X379921Y156220D02*
G03I-5906J0D01*
G01X342529Y530315D02*
G03X334655I-3937J0D01*
G01X342529Y520720D02*
G03X352474Y509057I11811J0D01*
G01X334655Y520720D02*
G03X351230Y501282I19685J0D01*
G01X384484Y503937D02*
X352475Y509057D01*
G01X383858Y496063D02*
X351231Y501282D01*
G01X442287Y503937D02*
X384484D01*
G01X442913Y496063D02*
X383858D01*
G01X342529Y530315D02*
Y520720D01*
G01X334655Y562992D02*
Y520720D01*
G01X346466Y570866D02*
G03X342529Y566929I0J-3937D01*
G01X334655Y555512D02*
G03X342529I3937J0D01*
G01X346466Y570866D02*
X480325D01*
G01X334655Y562992D02*
G03X326781Y570866I-7874J0D01*
G01X342529Y566929D02*
Y555512D01*
G01X415943Y539991D02*
G03I-4291J0D01*
G01X474316Y509060D02*
X442287Y503937D01*
G01X475560Y501285D02*
X442913Y496063D01*
G01X492136Y530315D02*
G03X484262I-3937J0D01*
G01X474316Y509060D02*
G03X484262Y520723I-1865J11663D01*
G01X475560Y501285D02*
G03X492136Y520723I-3109J19438D01*
G01X484262Y530315D02*
Y520723D01*
G01X492136Y562992D02*
Y520723D01*
G01X484262Y566929D02*
G03X480325Y570866I-3937J0D01*
G01X484262Y555512D02*
G03X492136I3937J0D01*
G01X500010Y570866D02*
G03X492136Y562992I0J-7874D01*
G01X500010Y570866D02*
X818897D01*
G01X484262Y566929D02*
Y555512D01*
G01X537401Y371299D02*
G03I-5905J0D01*
G01X538386Y531496D02*
G03I-6890J0D01*
G01X628416Y0D02*
G03Y-7874I0J-3937D01*
G01X597707D02*
G03Y0I0J3937D01*
G01X780315Y-7874D02*
X628416D01*
G01X602362Y116141D02*
G03I-5906J0D01*
G01X817003Y-86834D02*
G03I-4292J0D01*
G01X811771Y-102362D02*
G03X826771Y-87362I0J15000D01*
G01X811023Y0D02*
G03Y-7874I0J-3937D01*
G01X780315D02*
G03Y0I0J3937D01*
G01X822834Y-7874D02*
X811023D01*
G01X818897Y0D02*
G03X826771Y7874I0J7874D01*
G01X818897Y0D02*
X807086D01*
G01X787401Y198819D02*
G03I-5905J0D01*
G01X792421Y499724D02*
G03I-3051J0D01*
G01X793504Y535157D02*
G03I-4134J0D01*
G01X796653Y517441D02*
G03I-7283J0D01*
G01X826771Y562992D02*
G03X818897Y570866I-7874J0D01*
G01X826771Y-11811D02*
Y-87362D01*
G01Y-11811D02*
G03X822834Y-7874I-3937J0D01*
G01X826771Y562992D02*
Y7874D01*
M02*
